FILE_TYPE = MACRO_DRAWING;
SET COLOR_WIRE YELLOW;
SET COLOR_PROP ORANGE;
SET COLOR_DOT WHITE;
SET COLOR_ARC YELLOW;
SET COLOR_BODY GREEN;
SET COLOR_NOTE PURPLE;
SET PROP_DISPLAY VALUE;
SET PAGE_NUMBER P149;
FORCEADD OFFPAGE..2
R 2
(-2000 3600);
FORCEPROP 2 LAST $XR0 62 
J 0
(-2224 3600);
DISPLAY 0.638298 (-2224 3600);
PAINT MONO (-2224 3600);
FORCEPROP 1 LAST OFFPAGE TRUE
J 2
(-2325 3475);
DISPLAY 0.872340 (-2325 3475);
PAINT AQUA (-2325 3475);
DISPLAY INVISIBLE (-2325 3475);
FORCEPROP 1 LAST COMMENT_BODY TRUE
J 2
(-1955 3505);
DISPLAY 0.872340 (-1955 3505);
PAINT GREEN (-1955 3505);
DISPLAY INVISIBLE (-1955 3505);
FORCEPROP 2 LAST PATH I216
J 0
(-1950 3675);
DISPLAY 1.021277 (-1950 3675);
DISPLAY INVISIBLE (-1950 3675);
FORCEPROP 2 LAST CDS_LIB standard
J 0
(-2000 3600);
DISPLAY INVISIBLE (-2000 3600);
FORCEADD OFFPAGE..5
(-2000 3550);
FORCEPROP 2 LAST $XR0 62 
J 0
(-2224 3550);
DISPLAY 0.638298 (-2224 3550);
PAINT MONO (-2224 3550);
FORCEPROP 1 LAST OFFPAGE TRUE
J 0
(-1675 3425);
DISPLAY 0.872340 (-1675 3425);
PAINT AQUA (-1675 3425);
DISPLAY INVISIBLE (-1675 3425);
FORCEPROP 1 LAST COMMENT_BODY TRUE
J 0
(-1900 3475);
DISPLAY 1.170213 (-1900 3475);
PAINT GREEN (-1900 3475);
DISPLAY INVISIBLE (-1900 3475);
FORCEPROP 2 LAST PATH I217
J 0
(-1950 3625);
DISPLAY 1.021277 (-1950 3625);
DISPLAY INVISIBLE (-1950 3625);
FORCEPROP 2 LAST CDS_LIB standard
J 0
(-2000 3550);
DISPLAY INVISIBLE (-2000 3550);
FORCEADD OFFPAGE..5
(-2000 3700);
FORCEPROP 2 LAST $XR0 60 
J 0
(-2224 3700);
DISPLAY 0.638298 (-2224 3700);
PAINT MONO (-2224 3700);
FORCEPROP 1 LAST COMMENT_BODY TRUE
J 0
(-1900 3625);
DISPLAY 1.170213 (-1900 3625);
PAINT GREEN (-1900 3625);
DISPLAY INVISIBLE (-1900 3625);
FORCEPROP 1 LAST OFFPAGE TRUE
J 0
(-1675 3575);
DISPLAY 0.872340 (-1675 3575);
PAINT AQUA (-1675 3575);
DISPLAY INVISIBLE (-1675 3575);
FORCEPROP 2 LAST PATH I218
J 0
(-1950 3775);
DISPLAY 1.021277 (-1950 3775);
DISPLAY INVISIBLE (-1950 3775);
FORCEPROP 2 LAST CDS_LIB standard
J 0
(-2000 3700);
DISPLAY INVISIBLE (-2000 3700);
FORCEADD OFFPAGE..2
R 2
(-2000 3750);
FORCEPROP 2 LAST $XR0 60 
J 0
(-2224 3750);
DISPLAY 0.638298 (-2224 3750);
PAINT MONO (-2224 3750);
FORCEPROP 1 LAST OFFPAGE TRUE
J 2
(-2325 3625);
DISPLAY 0.872340 (-2325 3625);
PAINT AQUA (-2325 3625);
DISPLAY INVISIBLE (-2325 3625);
FORCEPROP 1 LAST COMMENT_BODY TRUE
J 2
(-1955 3655);
DISPLAY 0.872340 (-1955 3655);
PAINT GREEN (-1955 3655);
DISPLAY INVISIBLE (-1955 3655);
FORCEPROP 2 LAST PATH I219
J 0
(-1950 3825);
DISPLAY 1.021277 (-1950 3825);
DISPLAY INVISIBLE (-1950 3825);
FORCEPROP 2 LAST CDS_LIB standard
J 0
(-2000 3750);
DISPLAY INVISIBLE (-2000 3750);
FORCEADD OFFPAGE..4
R 2
(-2000 3250);
FORCEPROP 2 LAST $XR0 177 
J 0
(-2252 3250);
DISPLAY 0.638298 (-2252 3250);
PAINT MONO (-2252 3250);
FORCEPROP 2 LAST PATH I220
J 0
(-1950 3325);
DISPLAY 1.021277 (-1950 3325);
DISPLAY INVISIBLE (-1950 3325);
FORCEPROP 2 LAST CDS_LIB standard
J 0
(-2000 3250);
DISPLAY INVISIBLE (-2000 3250);
FORCEPROP 1 LAST COMMENT_BODY TRUE
J 2
(-1975 3150);
DISPLAY 0.872340 (-1975 3150);
PAINT GREEN (-1975 3150);
DISPLAY INVISIBLE (-1975 3150);
FORCEPROP 1 LAST OFFPAGE TRUE
J 2
(-2325 3125);
DISPLAY 0.872340 (-2325 3125);
PAINT GREEN (-2325 3125);
DISPLAY INVISIBLE (-2325 3125);
FORCEADD OFFPAGE..4
R 2
(-2000 3450);
FORCEPROP 2 LAST $XR0 176 
J 0
(-2252 3450);
DISPLAY 0.638298 (-2252 3450);
PAINT MONO (-2252 3450);
FORCEPROP 2 LAST PATH I221
J 0
(-1950 3525);
DISPLAY 1.021277 (-1950 3525);
DISPLAY INVISIBLE (-1950 3525);
FORCEPROP 2 LAST CDS_LIB standard
J 0
(-2000 3450);
DISPLAY INVISIBLE (-2000 3450);
FORCEPROP 1 LAST COMMENT_BODY TRUE
J 2
(-1975 3350);
DISPLAY 0.872340 (-1975 3350);
PAINT GREEN (-1975 3350);
DISPLAY INVISIBLE (-1975 3350);
FORCEPROP 1 LAST OFFPAGE TRUE
J 2
(-2325 3325);
DISPLAY 0.872340 (-2325 3325);
PAINT GREEN (-2325 3325);
DISPLAY INVISIBLE (-2325 3325);
FORCEADD OFFPAGE..4
R 2
(-2000 3300);
FORCEPROP 2 LAST $XR0 177 
J 0
(-2252 3300);
DISPLAY 0.638298 (-2252 3300);
PAINT MONO (-2252 3300);
FORCEPROP 2 LAST PATH I222
J 0
(-1950 3375);
DISPLAY 1.021277 (-1950 3375);
DISPLAY INVISIBLE (-1950 3375);
FORCEPROP 2 LAST CDS_LIB standard
J 0
(-2000 3300);
DISPLAY INVISIBLE (-2000 3300);
FORCEPROP 1 LAST COMMENT_BODY TRUE
J 2
(-1975 3200);
DISPLAY 0.872340 (-1975 3200);
PAINT GREEN (-1975 3200);
DISPLAY INVISIBLE (-1975 3200);
FORCEPROP 1 LAST OFFPAGE TRUE
J 2
(-2325 3175);
DISPLAY 0.872340 (-2325 3175);
PAINT GREEN (-2325 3175);
DISPLAY INVISIBLE (-2325 3175);
FORCEADD OFFPAGE..4
R 2
(-2000 3400);
FORCEPROP 2 LAST $XR0 176 
J 0
(-2252 3400);
DISPLAY 0.638298 (-2252 3400);
PAINT MONO (-2252 3400);
FORCEPROP 2 LAST PATH I223
J 0
(-1950 3475);
DISPLAY 1.021277 (-1950 3475);
DISPLAY INVISIBLE (-1950 3475);
FORCEPROP 2 LAST CDS_LIB standard
J 0
(-2000 3400);
DISPLAY INVISIBLE (-2000 3400);
FORCEPROP 1 LAST OFFPAGE TRUE
J 2
(-2325 3275);
DISPLAY 0.872340 (-2325 3275);
PAINT GREEN (-2325 3275);
DISPLAY INVISIBLE (-2325 3275);
FORCEPROP 1 LAST COMMENT_BODY TRUE
J 2
(-1975 3300);
DISPLAY 0.872340 (-1975 3300);
PAINT GREEN (-1975 3300);
DISPLAY INVISIBLE (-1975 3300);
FORCEADD OFFPAGE..2
R 2
(-2000 2600);
FORCEPROP 2 LAST $XR0 60 
J 0
(-2224 2600);
DISPLAY 0.638298 (-2224 2600);
PAINT MONO (-2224 2600);
FORCEPROP 2 LAST CDS_LIB standard
J 0
(-2000 2600);
DISPLAY INVISIBLE (-2000 2600);
FORCEPROP 2 LAST PATH I224
J 0
(-1950 2675);
DISPLAY 1.021277 (-1950 2675);
DISPLAY INVISIBLE (-1950 2675);
FORCEPROP 1 LAST OFFPAGE TRUE
J 2
(-2325 2475);
DISPLAY 0.872340 (-2325 2475);
PAINT AQUA (-2325 2475);
DISPLAY INVISIBLE (-2325 2475);
FORCEPROP 1 LAST COMMENT_BODY TRUE
J 2
(-1955 2505);
DISPLAY 0.872340 (-1955 2505);
PAINT GREEN (-1955 2505);
DISPLAY INVISIBLE (-1955 2505);
FORCEADD OFFPAGE..5
(-2000 2550);
FORCEPROP 2 LAST $XR0 60 
J 0
(-2224 2550);
DISPLAY 0.638298 (-2224 2550);
PAINT MONO (-2224 2550);
FORCEPROP 2 LAST CDS_LIB standard
J 0
(-2000 2550);
DISPLAY INVISIBLE (-2000 2550);
FORCEPROP 2 LAST PATH I225
J 0
(-1950 2625);
DISPLAY 1.021277 (-1950 2625);
DISPLAY INVISIBLE (-1950 2625);
FORCEPROP 1 LAST OFFPAGE TRUE
J 0
(-1675 2425);
DISPLAY 0.872340 (-1675 2425);
PAINT AQUA (-1675 2425);
DISPLAY INVISIBLE (-1675 2425);
FORCEPROP 1 LAST COMMENT_BODY TRUE
J 0
(-1900 2475);
DISPLAY 1.170213 (-1900 2475);
PAINT GREEN (-1900 2475);
DISPLAY INVISIBLE (-1900 2475);
FORCEADD OFFPAGE..2
R 2
(-2000 2450);
FORCEPROP 2 LAST $XR0 62 
J 0
(-2224 2450);
DISPLAY 0.638298 (-2224 2450);
PAINT MONO (-2224 2450);
FORCEPROP 2 LAST CDS_LIB standard
J 0
(-2000 2450);
DISPLAY INVISIBLE (-2000 2450);
FORCEPROP 2 LAST PATH I226
J 0
(-1950 2525);
DISPLAY 1.021277 (-1950 2525);
DISPLAY INVISIBLE (-1950 2525);
FORCEPROP 1 LAST COMMENT_BODY TRUE
J 2
(-1955 2355);
DISPLAY 0.872340 (-1955 2355);
PAINT GREEN (-1955 2355);
DISPLAY INVISIBLE (-1955 2355);
FORCEPROP 1 LAST OFFPAGE TRUE
J 2
(-2325 2325);
DISPLAY 0.872340 (-2325 2325);
PAINT AQUA (-2325 2325);
DISPLAY INVISIBLE (-2325 2325);
FORCEADD OFFPAGE..5
(-2000 2400);
FORCEPROP 2 LAST $XR0 62 
J 0
(-2224 2400);
DISPLAY 0.638298 (-2224 2400);
PAINT MONO (-2224 2400);
FORCEPROP 2 LAST CDS_LIB standard
J 0
(-2000 2400);
DISPLAY INVISIBLE (-2000 2400);
FORCEPROP 2 LAST PATH I227
J 0
(-1950 2475);
DISPLAY 1.021277 (-1950 2475);
DISPLAY INVISIBLE (-1950 2475);
FORCEPROP 1 LAST COMMENT_BODY TRUE
J 0
(-1900 2325);
DISPLAY 1.170213 (-1900 2325);
PAINT GREEN (-1900 2325);
DISPLAY INVISIBLE (-1900 2325);
FORCEPROP 1 LAST OFFPAGE TRUE
J 0
(-1675 2275);
DISPLAY 0.872340 (-1675 2275);
PAINT AQUA (-1675 2275);
DISPLAY INVISIBLE (-1675 2275);
FORCEADD OFFPAGE..4
R 2
(-2000 2250);
FORCEPROP 2 LAST $XR0 176 
J 0
(-2252 2250);
DISPLAY 0.638298 (-2252 2250);
PAINT MONO (-2252 2250);
FORCEPROP 2 LAST CDS_LIB standard
J 0
(-2000 2250);
DISPLAY INVISIBLE (-2000 2250);
FORCEPROP 2 LAST PATH I228
J 0
(-1950 2325);
DISPLAY 1.021277 (-1950 2325);
DISPLAY INVISIBLE (-1950 2325);
FORCEPROP 1 LAST OFFPAGE TRUE
J 2
(-2325 2125);
DISPLAY 0.872340 (-2325 2125);
PAINT GREEN (-2325 2125);
DISPLAY INVISIBLE (-2325 2125);
FORCEPROP 1 LAST COMMENT_BODY TRUE
J 2
(-1975 2150);
DISPLAY 0.872340 (-1975 2150);
PAINT GREEN (-1975 2150);
DISPLAY INVISIBLE (-1975 2150);
FORCEADD OFFPAGE..4
R 2
(-2000 2300);
FORCEPROP 2 LAST $XR0 176 
J 0
(-2252 2300);
DISPLAY 0.638298 (-2252 2300);
PAINT MONO (-2252 2300);
FORCEPROP 2 LAST CDS_LIB standard
J 0
(-2000 2300);
DISPLAY INVISIBLE (-2000 2300);
FORCEPROP 2 LAST PATH I229
J 0
(-1950 2375);
DISPLAY 1.021277 (-1950 2375);
DISPLAY INVISIBLE (-1950 2375);
FORCEPROP 1 LAST COMMENT_BODY TRUE
J 2
(-1975 2200);
DISPLAY 0.872340 (-1975 2200);
PAINT GREEN (-1975 2200);
DISPLAY INVISIBLE (-1975 2200);
FORCEPROP 1 LAST OFFPAGE TRUE
J 2
(-2325 2175);
DISPLAY 0.872340 (-2325 2175);
PAINT GREEN (-2325 2175);
DISPLAY INVISIBLE (-2325 2175);
FORCEADD OFFPAGE..4
R 2
(-2000 2100);
FORCEPROP 2 LAST $XR0 177 
J 0
(-2252 2100);
DISPLAY 0.638298 (-2252 2100);
PAINT MONO (-2252 2100);
FORCEPROP 2 LAST CDS_LIB standard
J 0
(-2000 2100);
DISPLAY INVISIBLE (-2000 2100);
FORCEPROP 2 LAST PATH I230
J 0
(-1950 2175);
DISPLAY 1.021277 (-1950 2175);
DISPLAY INVISIBLE (-1950 2175);
FORCEPROP 1 LAST COMMENT_BODY TRUE
J 2
(-1975 2000);
DISPLAY 0.872340 (-1975 2000);
PAINT GREEN (-1975 2000);
DISPLAY INVISIBLE (-1975 2000);
FORCEPROP 1 LAST OFFPAGE TRUE
J 2
(-2325 1975);
DISPLAY 0.872340 (-2325 1975);
PAINT GREEN (-2325 1975);
DISPLAY INVISIBLE (-2325 1975);
FORCEADD OFFPAGE..4
R 2
(-2000 2150);
FORCEPROP 2 LAST $XR0 177 
J 0
(-2252 2150);
DISPLAY 0.638298 (-2252 2150);
PAINT MONO (-2252 2150);
FORCEPROP 2 LAST CDS_LIB standard
J 0
(-2000 2150);
DISPLAY INVISIBLE (-2000 2150);
FORCEPROP 2 LAST PATH I231
J 0
(-1950 2225);
DISPLAY 1.021277 (-1950 2225);
DISPLAY INVISIBLE (-1950 2225);
FORCEPROP 1 LAST COMMENT_BODY TRUE
J 2
(-1975 2050);
DISPLAY 0.872340 (-1975 2050);
PAINT GREEN (-1975 2050);
DISPLAY INVISIBLE (-1975 2050);
FORCEPROP 1 LAST OFFPAGE TRUE
J 2
(-2325 2025);
DISPLAY 0.872340 (-2325 2025);
PAINT GREEN (-2325 2025);
DISPLAY INVISIBLE (-2325 2025);
FORCEADD OFFPAGE..4
R 2
(-1975 1100);
FORCEPROP 2 LAST $XR0 177 
J 0
(-2227 1100);
DISPLAY 0.638298 (-2227 1100);
PAINT MONO (-2227 1100);
FORCEPROP 1 LAST COMMENT_BODY TRUE
J 2
(-1950 1000);
DISPLAY 0.872340 (-1950 1000);
PAINT GREEN (-1950 1000);
DISPLAY INVISIBLE (-1950 1000);
FORCEPROP 1 LAST OFFPAGE TRUE
J 2
(-2300 975);
DISPLAY 0.872340 (-2300 975);
PAINT GREEN (-2300 975);
DISPLAY INVISIBLE (-2300 975);
FORCEPROP 2 LAST PATH I232
J 0
(-1925 1175);
DISPLAY 1.021277 (-1925 1175);
DISPLAY INVISIBLE (-1925 1175);
FORCEPROP 2 LAST CDS_LIB standard
J 0
(-1975 1100);
DISPLAY INVISIBLE (-1975 1100);
FORCEADD OFFPAGE..4
R 2
(-1975 1050);
FORCEPROP 2 LAST $XR0 177 
J 0
(-2227 1050);
DISPLAY 0.638298 (-2227 1050);
PAINT MONO (-2227 1050);
FORCEPROP 1 LAST COMMENT_BODY TRUE
J 2
(-1950 950);
DISPLAY 0.872340 (-1950 950);
PAINT GREEN (-1950 950);
DISPLAY INVISIBLE (-1950 950);
FORCEPROP 1 LAST OFFPAGE TRUE
J 2
(-2300 925);
DISPLAY 0.872340 (-2300 925);
PAINT GREEN (-2300 925);
DISPLAY INVISIBLE (-2300 925);
FORCEPROP 2 LAST PATH I233
J 0
(-1925 1125);
DISPLAY 1.021277 (-1925 1125);
DISPLAY INVISIBLE (-1925 1125);
FORCEPROP 2 LAST CDS_LIB standard
J 0
(-1975 1050);
DISPLAY INVISIBLE (-1975 1050);
FORCEADD OFFPAGE..4
R 2
(-1975 1250);
FORCEPROP 2 LAST $XR0 176 
J 0
(-2227 1250);
DISPLAY 0.638298 (-2227 1250);
PAINT MONO (-2227 1250);
FORCEPROP 2 LAST CDS_LIB standard
J 0
(-1975 1250);
DISPLAY INVISIBLE (-1975 1250);
FORCEPROP 2 LAST PATH I234
J 0
(-1925 1325);
DISPLAY 1.021277 (-1925 1325);
DISPLAY INVISIBLE (-1925 1325);
FORCEPROP 1 LAST OFFPAGE TRUE
J 2
(-2300 1125);
DISPLAY 0.872340 (-2300 1125);
PAINT GREEN (-2300 1125);
DISPLAY INVISIBLE (-2300 1125);
FORCEPROP 1 LAST COMMENT_BODY TRUE
J 2
(-1950 1150);
DISPLAY 0.872340 (-1950 1150);
PAINT GREEN (-1950 1150);
DISPLAY INVISIBLE (-1950 1150);
FORCEADD OFFPAGE..4
R 2
(-1975 1200);
FORCEPROP 2 LAST $XR0 176 
J 0
(-2227 1200);
DISPLAY 0.638298 (-2227 1200);
PAINT MONO (-2227 1200);
FORCEPROP 2 LAST CDS_LIB standard
J 0
(-1975 1200);
DISPLAY INVISIBLE (-1975 1200);
FORCEPROP 2 LAST PATH I235
J 0
(-1925 1275);
DISPLAY 1.021277 (-1925 1275);
DISPLAY INVISIBLE (-1925 1275);
FORCEPROP 1 LAST COMMENT_BODY TRUE
J 2
(-1950 1100);
DISPLAY 0.872340 (-1950 1100);
PAINT GREEN (-1950 1100);
DISPLAY INVISIBLE (-1950 1100);
FORCEPROP 1 LAST OFFPAGE TRUE
J 2
(-2300 1075);
DISPLAY 0.872340 (-2300 1075);
PAINT GREEN (-2300 1075);
DISPLAY INVISIBLE (-2300 1075);
FORCEADD OFFPAGE..5
(-1975 1350);
FORCEPROP 2 LAST $XR0 62 
J 0
(-2199 1350);
DISPLAY 0.638298 (-2199 1350);
PAINT MONO (-2199 1350);
FORCEPROP 1 LAST COMMENT_BODY TRUE
J 0
(-1875 1275);
DISPLAY 1.170213 (-1875 1275);
PAINT GREEN (-1875 1275);
DISPLAY INVISIBLE (-1875 1275);
FORCEPROP 1 LAST OFFPAGE TRUE
J 0
(-1650 1225);
DISPLAY 0.872340 (-1650 1225);
PAINT AQUA (-1650 1225);
DISPLAY INVISIBLE (-1650 1225);
FORCEPROP 2 LAST PATH I236
J 0
(-1925 1425);
DISPLAY 1.021277 (-1925 1425);
DISPLAY INVISIBLE (-1925 1425);
FORCEPROP 2 LAST CDS_LIB standard
J 0
(-1975 1350);
DISPLAY INVISIBLE (-1975 1350);
FORCEADD OFFPAGE..2
R 2
(-1975 1400);
FORCEPROP 2 LAST $XR0 62 
J 0
(-2199 1400);
DISPLAY 0.638298 (-2199 1400);
PAINT MONO (-2199 1400);
FORCEPROP 1 LAST COMMENT_BODY TRUE
J 2
(-1930 1305);
DISPLAY 0.872340 (-1930 1305);
PAINT GREEN (-1930 1305);
DISPLAY INVISIBLE (-1930 1305);
FORCEPROP 1 LAST OFFPAGE TRUE
J 2
(-2300 1275);
DISPLAY 0.872340 (-2300 1275);
PAINT AQUA (-2300 1275);
DISPLAY INVISIBLE (-2300 1275);
FORCEPROP 2 LAST PATH I237
J 0
(-1925 1475);
DISPLAY 1.021277 (-1925 1475);
DISPLAY INVISIBLE (-1925 1475);
FORCEPROP 2 LAST CDS_LIB standard
J 0
(-1975 1400);
DISPLAY INVISIBLE (-1975 1400);
FORCEADD OFFPAGE..5
(-1975 1500);
FORCEPROP 2 LAST $XR0 60 
J 0
(-2199 1500);
DISPLAY 0.638298 (-2199 1500);
PAINT MONO (-2199 1500);
FORCEPROP 2 LAST CDS_LIB standard
J 0
(-1975 1500);
DISPLAY INVISIBLE (-1975 1500);
FORCEPROP 2 LAST PATH I238
J 0
(-1925 1575);
DISPLAY 1.021277 (-1925 1575);
DISPLAY INVISIBLE (-1925 1575);
FORCEPROP 1 LAST COMMENT_BODY TRUE
J 0
(-1875 1425);
DISPLAY 1.170213 (-1875 1425);
PAINT GREEN (-1875 1425);
DISPLAY INVISIBLE (-1875 1425);
FORCEPROP 1 LAST OFFPAGE TRUE
J 0
(-1650 1375);
DISPLAY 0.872340 (-1650 1375);
PAINT AQUA (-1650 1375);
DISPLAY INVISIBLE (-1650 1375);
FORCEADD OFFPAGE..2
R 2
(-1975 1550);
FORCEPROP 2 LAST $XR0 60 
J 0
(-2199 1550);
DISPLAY 0.638298 (-2199 1550);
PAINT MONO (-2199 1550);
FORCEPROP 2 LAST CDS_LIB standard
J 0
(-1975 1550);
DISPLAY INVISIBLE (-1975 1550);
FORCEPROP 2 LAST PATH I239
J 0
(-1925 1625);
DISPLAY 1.021277 (-1925 1625);
DISPLAY INVISIBLE (-1925 1625);
FORCEPROP 1 LAST OFFPAGE TRUE
J 2
(-2300 1425);
DISPLAY 0.872340 (-2300 1425);
PAINT AQUA (-2300 1425);
DISPLAY INVISIBLE (-2300 1425);
FORCEPROP 1 LAST COMMENT_BODY TRUE
J 2
(-1930 1455);
DISPLAY 0.872340 (-1930 1455);
PAINT GREEN (-1930 1455);
DISPLAY INVISIBLE (-1930 1455);
FORCEADD OFFPAGE..4
R 2
(-1975 -50);
FORCEPROP 2 LAST $XR0 177 
J 0
(-2227 -50);
DISPLAY 0.638298 (-2227 -50);
PAINT MONO (-2227 -50);
FORCEPROP 1 LAST COMMENT_BODY TRUE
J 2
(-1950 -150);
DISPLAY 0.872340 (-1950 -150);
PAINT GREEN (-1950 -150);
DISPLAY INVISIBLE (-1950 -150);
FORCEPROP 1 LAST OFFPAGE TRUE
J 2
(-2300 -175);
DISPLAY 0.872340 (-2300 -175);
PAINT GREEN (-2300 -175);
DISPLAY INVISIBLE (-2300 -175);
FORCEPROP 2 LAST PATH I240
J 0
(-1925 25);
DISPLAY 1.021277 (-1925 25);
DISPLAY INVISIBLE (-1925 25);
FORCEPROP 2 LAST CDS_LIB standard
J 0
(-1975 -50);
DISPLAY INVISIBLE (-1975 -50);
FORCEADD OFFPAGE..4
R 2
(-1975 -100);
FORCEPROP 2 LAST $XR0 177 
J 0
(-2227 -100);
DISPLAY 0.638298 (-2227 -100);
PAINT MONO (-2227 -100);
FORCEPROP 1 LAST COMMENT_BODY TRUE
J 2
(-1950 -200);
DISPLAY 0.872340 (-1950 -200);
PAINT GREEN (-1950 -200);
DISPLAY INVISIBLE (-1950 -200);
FORCEPROP 1 LAST OFFPAGE TRUE
J 2
(-2300 -225);
DISPLAY 0.872340 (-2300 -225);
PAINT GREEN (-2300 -225);
DISPLAY INVISIBLE (-2300 -225);
FORCEPROP 2 LAST PATH I241
J 0
(-1925 -25);
DISPLAY 1.021277 (-1925 -25);
DISPLAY INVISIBLE (-1925 -25);
FORCEPROP 2 LAST CDS_LIB standard
J 0
(-1975 -100);
DISPLAY INVISIBLE (-1975 -100);
FORCEADD OFFPAGE..4
R 2
(-1975 100);
FORCEPROP 2 LAST $XR0 176 
J 0
(-2227 100);
DISPLAY 0.638298 (-2227 100);
PAINT MONO (-2227 100);
FORCEPROP 2 LAST CDS_LIB standard
J 0
(-1975 100);
DISPLAY INVISIBLE (-1975 100);
FORCEPROP 2 LAST PATH I242
J 0
(-1925 175);
DISPLAY 1.021277 (-1925 175);
DISPLAY INVISIBLE (-1925 175);
FORCEPROP 1 LAST OFFPAGE TRUE
J 2
(-2300 -25);
DISPLAY 0.872340 (-2300 -25);
PAINT GREEN (-2300 -25);
DISPLAY INVISIBLE (-2300 -25);
FORCEPROP 1 LAST COMMENT_BODY TRUE
J 2
(-1950 0);
DISPLAY 0.872340 (-1950 0);
PAINT GREEN (-1950 0);
DISPLAY INVISIBLE (-1950 0);
FORCEADD OFFPAGE..4
R 2
(-1975 50);
FORCEPROP 2 LAST $XR0 176 
J 0
(-2227 50);
DISPLAY 0.638298 (-2227 50);
PAINT MONO (-2227 50);
FORCEPROP 2 LAST CDS_LIB standard
J 0
(-1975 50);
DISPLAY INVISIBLE (-1975 50);
FORCEPROP 2 LAST PATH I243
J 0
(-1925 125);
DISPLAY 1.021277 (-1925 125);
DISPLAY INVISIBLE (-1925 125);
FORCEPROP 1 LAST COMMENT_BODY TRUE
J 2
(-1950 -50);
DISPLAY 0.872340 (-1950 -50);
PAINT GREEN (-1950 -50);
DISPLAY INVISIBLE (-1950 -50);
FORCEPROP 1 LAST OFFPAGE TRUE
J 2
(-2300 -75);
DISPLAY 0.872340 (-2300 -75);
PAINT GREEN (-2300 -75);
DISPLAY INVISIBLE (-2300 -75);
FORCEADD OFFPAGE..5
(-1975 200);
FORCEPROP 2 LAST $XR0 62 
J 0
(-2199 200);
DISPLAY 0.638298 (-2199 200);
PAINT MONO (-2199 200);
FORCEPROP 1 LAST COMMENT_BODY TRUE
J 0
(-1875 125);
DISPLAY 1.170213 (-1875 125);
PAINT GREEN (-1875 125);
DISPLAY INVISIBLE (-1875 125);
FORCEPROP 1 LAST OFFPAGE TRUE
J 0
(-1650 75);
DISPLAY 0.872340 (-1650 75);
PAINT AQUA (-1650 75);
DISPLAY INVISIBLE (-1650 75);
FORCEPROP 2 LAST PATH I244
J 0
(-1925 275);
DISPLAY 1.021277 (-1925 275);
DISPLAY INVISIBLE (-1925 275);
FORCEPROP 2 LAST CDS_LIB standard
J 0
(-1975 200);
DISPLAY INVISIBLE (-1975 200);
FORCEADD OFFPAGE..2
R 2
(-1975 250);
FORCEPROP 2 LAST $XR0 62 
J 0
(-2199 250);
DISPLAY 0.638298 (-2199 250);
PAINT MONO (-2199 250);
FORCEPROP 1 LAST COMMENT_BODY TRUE
J 2
(-1930 155);
DISPLAY 0.872340 (-1930 155);
PAINT GREEN (-1930 155);
DISPLAY INVISIBLE (-1930 155);
FORCEPROP 1 LAST OFFPAGE TRUE
J 2
(-2300 125);
DISPLAY 0.872340 (-2300 125);
PAINT AQUA (-2300 125);
DISPLAY INVISIBLE (-2300 125);
FORCEPROP 2 LAST PATH I245
J 0
(-1925 325);
DISPLAY 1.021277 (-1925 325);
DISPLAY INVISIBLE (-1925 325);
FORCEPROP 2 LAST CDS_LIB standard
J 0
(-1975 250);
DISPLAY INVISIBLE (-1975 250);
FORCEADD OFFPAGE..5
(-1975 350);
FORCEPROP 2 LAST $XR0 60 
J 0
(-2199 350);
DISPLAY 0.638298 (-2199 350);
PAINT MONO (-2199 350);
FORCEPROP 2 LAST CDS_LIB standard
J 0
(-1975 350);
DISPLAY INVISIBLE (-1975 350);
FORCEPROP 2 LAST PATH I246
J 0
(-1925 425);
DISPLAY 1.021277 (-1925 425);
DISPLAY INVISIBLE (-1925 425);
FORCEPROP 1 LAST COMMENT_BODY TRUE
J 0
(-1875 275);
DISPLAY 1.170213 (-1875 275);
PAINT GREEN (-1875 275);
DISPLAY INVISIBLE (-1875 275);
FORCEPROP 1 LAST OFFPAGE TRUE
J 0
(-1650 225);
DISPLAY 0.872340 (-1650 225);
PAINT AQUA (-1650 225);
DISPLAY INVISIBLE (-1650 225);
FORCEADD OFFPAGE..2
R 2
(-1975 400);
FORCEPROP 2 LAST $XR0 60 
J 0
(-2199 400);
DISPLAY 0.638298 (-2199 400);
PAINT MONO (-2199 400);
FORCEPROP 2 LAST CDS_LIB standard
J 0
(-1975 400);
DISPLAY INVISIBLE (-1975 400);
FORCEPROP 2 LAST PATH I247
J 0
(-1925 475);
DISPLAY 1.021277 (-1925 475);
DISPLAY INVISIBLE (-1925 475);
FORCEPROP 1 LAST OFFPAGE TRUE
J 2
(-2300 275);
DISPLAY 0.872340 (-2300 275);
PAINT AQUA (-2300 275);
DISPLAY INVISIBLE (-2300 275);
FORCEPROP 1 LAST COMMENT_BODY TRUE
J 2
(-1930 305);
DISPLAY 0.872340 (-1930 305);
PAINT GREEN (-1930 305);
DISPLAY INVISIBLE (-1930 305);
FORCEADD OFFPAGE..4
R 2
(2650 3375);
FORCEPROP 2 LAST $XR0 177 
J 0
(2398 3375);
DISPLAY 0.638298 (2398 3375);
PAINT MONO (2398 3375);
FORCEPROP 2 LAST CDS_LIB standard
J 0
(2650 3375);
DISPLAY INVISIBLE (2650 3375);
FORCEPROP 2 LAST PATH I248
J 0
(2700 3450);
DISPLAY 1.021277 (2700 3450);
DISPLAY INVISIBLE (2700 3450);
FORCEPROP 1 LAST COMMENT_BODY TRUE
J 2
(2675 3275);
DISPLAY 0.872340 (2675 3275);
PAINT GREEN (2675 3275);
DISPLAY INVISIBLE (2675 3275);
FORCEPROP 1 LAST OFFPAGE TRUE
J 2
(2325 3250);
DISPLAY 0.872340 (2325 3250);
PAINT GREEN (2325 3250);
DISPLAY INVISIBLE (2325 3250);
FORCEADD OFFPAGE..4
R 2
(2650 3325);
FORCEPROP 2 LAST $XR0 177 
J 0
(2398 3325);
DISPLAY 0.638298 (2398 3325);
PAINT MONO (2398 3325);
FORCEPROP 2 LAST CDS_LIB standard
J 0
(2650 3325);
DISPLAY INVISIBLE (2650 3325);
FORCEPROP 2 LAST PATH I249
J 0
(2700 3400);
DISPLAY 1.021277 (2700 3400);
DISPLAY INVISIBLE (2700 3400);
FORCEPROP 1 LAST COMMENT_BODY TRUE
J 2
(2675 3225);
DISPLAY 0.872340 (2675 3225);
PAINT GREEN (2675 3225);
DISPLAY INVISIBLE (2675 3225);
FORCEPROP 1 LAST OFFPAGE TRUE
J 2
(2325 3200);
DISPLAY 0.872340 (2325 3200);
PAINT GREEN (2325 3200);
DISPLAY INVISIBLE (2325 3200);
FORCEADD OFFPAGE..4
R 2
(2650 3525);
FORCEPROP 2 LAST $XR0 176 
J 0
(2398 3525);
DISPLAY 0.638298 (2398 3525);
PAINT MONO (2398 3525);
FORCEPROP 2 LAST CDS_LIB standard
J 0
(2650 3525);
DISPLAY INVISIBLE (2650 3525);
FORCEPROP 2 LAST PATH I250
J 0
(2700 3600);
DISPLAY 1.021277 (2700 3600);
DISPLAY INVISIBLE (2700 3600);
FORCEPROP 1 LAST OFFPAGE TRUE
J 2
(2325 3400);
DISPLAY 0.872340 (2325 3400);
PAINT GREEN (2325 3400);
DISPLAY INVISIBLE (2325 3400);
FORCEPROP 1 LAST COMMENT_BODY TRUE
J 2
(2675 3425);
DISPLAY 0.872340 (2675 3425);
PAINT GREEN (2675 3425);
DISPLAY INVISIBLE (2675 3425);
FORCEADD OFFPAGE..4
R 2
(2650 3475);
FORCEPROP 2 LAST $XR0 176 
J 0
(2398 3475);
DISPLAY 0.638298 (2398 3475);
PAINT MONO (2398 3475);
FORCEPROP 2 LAST CDS_LIB standard
J 0
(2650 3475);
DISPLAY INVISIBLE (2650 3475);
FORCEPROP 2 LAST PATH I251
J 0
(2700 3550);
DISPLAY 1.021277 (2700 3550);
DISPLAY INVISIBLE (2700 3550);
FORCEPROP 1 LAST COMMENT_BODY TRUE
J 2
(2675 3375);
DISPLAY 0.872340 (2675 3375);
PAINT GREEN (2675 3375);
DISPLAY INVISIBLE (2675 3375);
FORCEPROP 1 LAST OFFPAGE TRUE
J 2
(2325 3350);
DISPLAY 0.872340 (2325 3350);
PAINT GREEN (2325 3350);
DISPLAY INVISIBLE (2325 3350);
FORCEADD OFFPAGE..5
(2650 3625);
FORCEPROP 2 LAST $XR0 62 
J 0
(2396 3625);
DISPLAY 0.638298 (2396 3625);
PAINT MONO (2396 3625);
FORCEPROP 1 LAST COMMENT_BODY TRUE
J 0
(2750 3550);
DISPLAY 1.170213 (2750 3550);
PAINT GREEN (2750 3550);
DISPLAY INVISIBLE (2750 3550);
FORCEPROP 1 LAST OFFPAGE TRUE
J 0
(2975 3500);
DISPLAY 0.872340 (2975 3500);
PAINT AQUA (2975 3500);
DISPLAY INVISIBLE (2975 3500);
FORCEPROP 2 LAST PATH I252
J 0
(2700 3700);
DISPLAY 1.021277 (2700 3700);
DISPLAY INVISIBLE (2700 3700);
FORCEPROP 2 LAST CDS_LIB standard
J 0
(2650 3625);
DISPLAY INVISIBLE (2650 3625);
FORCEADD OFFPAGE..2
R 2
(2650 3675);
FORCEPROP 2 LAST $XR0 62 
J 0
(2396 3675);
DISPLAY 0.638298 (2396 3675);
PAINT MONO (2396 3675);
FORCEPROP 1 LAST COMMENT_BODY TRUE
J 2
(2695 3580);
DISPLAY 0.872340 (2695 3580);
PAINT GREEN (2695 3580);
DISPLAY INVISIBLE (2695 3580);
FORCEPROP 1 LAST OFFPAGE TRUE
J 2
(2325 3550);
DISPLAY 0.872340 (2325 3550);
PAINT AQUA (2325 3550);
DISPLAY INVISIBLE (2325 3550);
FORCEPROP 2 LAST PATH I253
J 0
(2700 3750);
DISPLAY 1.021277 (2700 3750);
DISPLAY INVISIBLE (2700 3750);
FORCEPROP 2 LAST CDS_LIB standard
J 0
(2650 3675);
DISPLAY INVISIBLE (2650 3675);
FORCEADD OFFPAGE..5
(2650 3775);
FORCEPROP 2 LAST $XR0 60 
J 0
(2396 3775);
DISPLAY 0.638298 (2396 3775);
PAINT MONO (2396 3775);
FORCEPROP 2 LAST CDS_LIB standard
J 0
(2650 3775);
DISPLAY INVISIBLE (2650 3775);
FORCEPROP 2 LAST PATH I254
J 0
(2700 3850);
DISPLAY 1.021277 (2700 3850);
DISPLAY INVISIBLE (2700 3850);
FORCEPROP 1 LAST COMMENT_BODY TRUE
J 0
(2750 3700);
DISPLAY 1.170213 (2750 3700);
PAINT GREEN (2750 3700);
DISPLAY INVISIBLE (2750 3700);
FORCEPROP 1 LAST OFFPAGE TRUE
J 0
(2975 3650);
DISPLAY 0.872340 (2975 3650);
PAINT AQUA (2975 3650);
DISPLAY INVISIBLE (2975 3650);
FORCEADD OFFPAGE..2
R 2
(2650 3825);
FORCEPROP 2 LAST $XR0 60 
J 0
(2396 3825);
DISPLAY 0.638298 (2396 3825);
PAINT MONO (2396 3825);
FORCEPROP 2 LAST CDS_LIB standard
J 0
(2650 3825);
DISPLAY INVISIBLE (2650 3825);
FORCEPROP 2 LAST PATH I255
J 0
(2700 3900);
DISPLAY 1.021277 (2700 3900);
DISPLAY INVISIBLE (2700 3900);
FORCEPROP 1 LAST OFFPAGE TRUE
J 2
(2325 3700);
DISPLAY 0.872340 (2325 3700);
PAINT AQUA (2325 3700);
DISPLAY INVISIBLE (2325 3700);
FORCEPROP 1 LAST COMMENT_BODY TRUE
J 2
(2695 3730);
DISPLAY 0.872340 (2695 3730);
PAINT GREEN (2695 3730);
DISPLAY INVISIBLE (2695 3730);
FORCEADD OFFPAGE..4
R 2
(2650 2225);
FORCEPROP 2 LAST $XR0 177 
J 0
(2398 2225);
DISPLAY 0.638298 (2398 2225);
PAINT MONO (2398 2225);
FORCEPROP 1 LAST COMMENT_BODY TRUE
J 2
(2675 2125);
DISPLAY 0.872340 (2675 2125);
PAINT GREEN (2675 2125);
DISPLAY INVISIBLE (2675 2125);
FORCEPROP 1 LAST OFFPAGE TRUE
J 2
(2325 2100);
DISPLAY 0.872340 (2325 2100);
PAINT GREEN (2325 2100);
DISPLAY INVISIBLE (2325 2100);
FORCEPROP 2 LAST PATH I256
J 0
(2700 2300);
DISPLAY 1.021277 (2700 2300);
DISPLAY INVISIBLE (2700 2300);
FORCEPROP 2 LAST CDS_LIB standard
J 0
(2650 2225);
DISPLAY INVISIBLE (2650 2225);
FORCEADD OFFPAGE..4
R 2
(2650 2175);
FORCEPROP 2 LAST $XR0 177 
J 0
(2398 2175);
DISPLAY 0.638298 (2398 2175);
PAINT MONO (2398 2175);
FORCEPROP 1 LAST COMMENT_BODY TRUE
J 2
(2675 2075);
DISPLAY 0.872340 (2675 2075);
PAINT GREEN (2675 2075);
DISPLAY INVISIBLE (2675 2075);
FORCEPROP 1 LAST OFFPAGE TRUE
J 2
(2325 2050);
DISPLAY 0.872340 (2325 2050);
PAINT GREEN (2325 2050);
DISPLAY INVISIBLE (2325 2050);
FORCEPROP 2 LAST PATH I257
J 0
(2700 2250);
DISPLAY 1.021277 (2700 2250);
DISPLAY INVISIBLE (2700 2250);
FORCEPROP 2 LAST CDS_LIB standard
J 0
(2650 2175);
DISPLAY INVISIBLE (2650 2175);
FORCEADD OFFPAGE..4
R 2
(2650 2375);
FORCEPROP 2 LAST $XR0 176 
J 0
(2398 2375);
DISPLAY 0.638298 (2398 2375);
PAINT MONO (2398 2375);
FORCEPROP 1 LAST COMMENT_BODY TRUE
J 2
(2675 2275);
DISPLAY 0.872340 (2675 2275);
PAINT GREEN (2675 2275);
DISPLAY INVISIBLE (2675 2275);
FORCEPROP 1 LAST OFFPAGE TRUE
J 2
(2325 2250);
DISPLAY 0.872340 (2325 2250);
PAINT GREEN (2325 2250);
DISPLAY INVISIBLE (2325 2250);
FORCEPROP 2 LAST PATH I258
J 0
(2700 2450);
DISPLAY 1.021277 (2700 2450);
DISPLAY INVISIBLE (2700 2450);
FORCEPROP 2 LAST CDS_LIB standard
J 0
(2650 2375);
DISPLAY INVISIBLE (2650 2375);
FORCEADD OFFPAGE..4
R 2
(2650 2325);
FORCEPROP 2 LAST $XR0 176 
J 0
(2398 2325);
DISPLAY 0.638298 (2398 2325);
PAINT MONO (2398 2325);
FORCEPROP 2 LAST CDS_LIB standard
J 0
(2650 2325);
DISPLAY INVISIBLE (2650 2325);
FORCEPROP 2 LAST PATH I259
J 0
(2700 2400);
DISPLAY 1.021277 (2700 2400);
DISPLAY INVISIBLE (2700 2400);
FORCEPROP 1 LAST COMMENT_BODY TRUE
J 2
(2675 2225);
DISPLAY 0.872340 (2675 2225);
PAINT GREEN (2675 2225);
DISPLAY INVISIBLE (2675 2225);
FORCEPROP 1 LAST OFFPAGE TRUE
J 2
(2325 2200);
DISPLAY 0.872340 (2325 2200);
PAINT GREEN (2325 2200);
DISPLAY INVISIBLE (2325 2200);
FORCEADD OFFPAGE..5
(2650 2475);
FORCEPROP 2 LAST $XR0 62 
J 0
(2396 2475);
DISPLAY 0.638298 (2396 2475);
PAINT MONO (2396 2475);
FORCEPROP 2 LAST CDS_LIB standard
J 0
(2650 2475);
DISPLAY INVISIBLE (2650 2475);
FORCEPROP 2 LAST PATH I260
J 0
(2700 2550);
DISPLAY 1.021277 (2700 2550);
DISPLAY INVISIBLE (2700 2550);
FORCEPROP 1 LAST OFFPAGE TRUE
J 0
(2975 2350);
DISPLAY 0.872340 (2975 2350);
PAINT AQUA (2975 2350);
DISPLAY INVISIBLE (2975 2350);
FORCEPROP 1 LAST COMMENT_BODY TRUE
J 0
(2750 2400);
DISPLAY 1.170213 (2750 2400);
PAINT GREEN (2750 2400);
DISPLAY INVISIBLE (2750 2400);
FORCEADD OFFPAGE..2
R 2
(2650 2525);
FORCEPROP 2 LAST $XR0 62 
J 0
(2396 2525);
DISPLAY 0.638298 (2396 2525);
PAINT MONO (2396 2525);
FORCEPROP 2 LAST CDS_LIB standard
J 0
(2650 2525);
DISPLAY INVISIBLE (2650 2525);
FORCEPROP 2 LAST PATH I261
J 0
(2700 2600);
DISPLAY 1.021277 (2700 2600);
DISPLAY INVISIBLE (2700 2600);
FORCEPROP 1 LAST OFFPAGE TRUE
J 2
(2325 2400);
DISPLAY 0.872340 (2325 2400);
PAINT AQUA (2325 2400);
DISPLAY INVISIBLE (2325 2400);
FORCEPROP 1 LAST COMMENT_BODY TRUE
J 2
(2695 2430);
DISPLAY 0.872340 (2695 2430);
PAINT GREEN (2695 2430);
DISPLAY INVISIBLE (2695 2430);
FORCEADD OFFPAGE..5
(2650 2625);
FORCEPROP 2 LAST $XR0 60 
J 0
(2396 2625);
DISPLAY 0.638298 (2396 2625);
PAINT MONO (2396 2625);
FORCEPROP 2 LAST CDS_LIB standard
J 0
(2650 2625);
DISPLAY INVISIBLE (2650 2625);
FORCEPROP 2 LAST PATH I262
J 0
(2700 2700);
DISPLAY 1.021277 (2700 2700);
DISPLAY INVISIBLE (2700 2700);
FORCEPROP 1 LAST COMMENT_BODY TRUE
J 0
(2750 2550);
DISPLAY 1.170213 (2750 2550);
PAINT GREEN (2750 2550);
DISPLAY INVISIBLE (2750 2550);
FORCEPROP 1 LAST OFFPAGE TRUE
J 0
(2975 2500);
DISPLAY 0.872340 (2975 2500);
PAINT AQUA (2975 2500);
DISPLAY INVISIBLE (2975 2500);
FORCEADD OFFPAGE..2
R 2
(2650 2675);
FORCEPROP 2 LAST $XR0 60 
J 0
(2396 2675);
DISPLAY 0.638298 (2396 2675);
PAINT MONO (2396 2675);
FORCEPROP 2 LAST CDS_LIB standard
J 0
(2650 2675);
DISPLAY INVISIBLE (2650 2675);
FORCEPROP 2 LAST PATH I263
J 0
(2700 2750);
DISPLAY 1.021277 (2700 2750);
DISPLAY INVISIBLE (2700 2750);
FORCEPROP 1 LAST OFFPAGE TRUE
J 2
(2325 2550);
DISPLAY 0.872340 (2325 2550);
PAINT AQUA (2325 2550);
DISPLAY INVISIBLE (2325 2550);
FORCEPROP 1 LAST COMMENT_BODY TRUE
J 2
(2695 2580);
DISPLAY 0.872340 (2695 2580);
PAINT GREEN (2695 2580);
DISPLAY INVISIBLE (2695 2580);
FORCEADD OFFPAGE..4
R 2
(2650 1175);
FORCEPROP 2 LAST $XR0 177 
J 0
(2398 1175);
DISPLAY 0.638298 (2398 1175);
PAINT MONO (2398 1175);
FORCEPROP 2 LAST CDS_LIB standard
J 0
(2650 1175);
DISPLAY INVISIBLE (2650 1175);
FORCEPROP 2 LAST PATH I264
J 0
(2700 1250);
DISPLAY 1.021277 (2700 1250);
DISPLAY INVISIBLE (2700 1250);
FORCEPROP 1 LAST OFFPAGE TRUE
J 2
(2325 1050);
DISPLAY 0.872340 (2325 1050);
PAINT GREEN (2325 1050);
DISPLAY INVISIBLE (2325 1050);
FORCEPROP 1 LAST COMMENT_BODY TRUE
J 2
(2675 1075);
DISPLAY 0.872340 (2675 1075);
PAINT GREEN (2675 1075);
DISPLAY INVISIBLE (2675 1075);
FORCEADD OFFPAGE..4
R 2
(2650 1125);
FORCEPROP 2 LAST $XR0 177 
J 0
(2398 1125);
DISPLAY 0.638298 (2398 1125);
PAINT MONO (2398 1125);
FORCEPROP 1 LAST COMMENT_BODY TRUE
J 2
(2675 1025);
DISPLAY 0.872340 (2675 1025);
PAINT GREEN (2675 1025);
DISPLAY INVISIBLE (2675 1025);
FORCEPROP 1 LAST OFFPAGE TRUE
J 2
(2325 1000);
DISPLAY 0.872340 (2325 1000);
PAINT GREEN (2325 1000);
DISPLAY INVISIBLE (2325 1000);
FORCEPROP 2 LAST PATH I265
J 0
(2700 1200);
DISPLAY 1.021277 (2700 1200);
DISPLAY INVISIBLE (2700 1200);
FORCEPROP 2 LAST CDS_LIB standard
J 0
(2650 1125);
DISPLAY INVISIBLE (2650 1125);
FORCEADD OFFPAGE..4
R 2
(2650 1325);
FORCEPROP 2 LAST $XR0 176 
J 0
(2398 1325);
DISPLAY 0.638298 (2398 1325);
PAINT MONO (2398 1325);
FORCEPROP 2 LAST CDS_LIB standard
J 0
(2650 1325);
DISPLAY INVISIBLE (2650 1325);
FORCEPROP 2 LAST PATH I266
J 0
(2700 1400);
DISPLAY 1.021277 (2700 1400);
DISPLAY INVISIBLE (2700 1400);
FORCEPROP 1 LAST OFFPAGE TRUE
J 2
(2325 1200);
DISPLAY 0.872340 (2325 1200);
PAINT GREEN (2325 1200);
DISPLAY INVISIBLE (2325 1200);
FORCEPROP 1 LAST COMMENT_BODY TRUE
J 2
(2675 1225);
DISPLAY 0.872340 (2675 1225);
PAINT GREEN (2675 1225);
DISPLAY INVISIBLE (2675 1225);
FORCEADD OFFPAGE..4
R 2
(2650 1275);
FORCEPROP 2 LAST $XR0 176 
J 0
(2398 1275);
DISPLAY 0.638298 (2398 1275);
PAINT MONO (2398 1275);
FORCEPROP 2 LAST CDS_LIB standard
J 0
(2650 1275);
DISPLAY INVISIBLE (2650 1275);
FORCEPROP 2 LAST PATH I267
J 0
(2700 1350);
DISPLAY 1.021277 (2700 1350);
DISPLAY INVISIBLE (2700 1350);
FORCEPROP 1 LAST COMMENT_BODY TRUE
J 2
(2675 1175);
DISPLAY 0.872340 (2675 1175);
PAINT GREEN (2675 1175);
DISPLAY INVISIBLE (2675 1175);
FORCEPROP 1 LAST OFFPAGE TRUE
J 2
(2325 1150);
DISPLAY 0.872340 (2325 1150);
PAINT GREEN (2325 1150);
DISPLAY INVISIBLE (2325 1150);
FORCEADD OFFPAGE..5
(2650 1425);
FORCEPROP 2 LAST $XR0 62 
J 0
(2396 1425);
DISPLAY 0.638298 (2396 1425);
PAINT MONO (2396 1425);
FORCEPROP 1 LAST COMMENT_BODY TRUE
J 0
(2750 1350);
DISPLAY 1.170213 (2750 1350);
PAINT GREEN (2750 1350);
DISPLAY INVISIBLE (2750 1350);
FORCEPROP 1 LAST OFFPAGE TRUE
J 0
(2975 1300);
DISPLAY 0.872340 (2975 1300);
PAINT AQUA (2975 1300);
DISPLAY INVISIBLE (2975 1300);
FORCEPROP 2 LAST PATH I268
J 0
(2700 1500);
DISPLAY 1.021277 (2700 1500);
DISPLAY INVISIBLE (2700 1500);
FORCEPROP 2 LAST CDS_LIB standard
J 0
(2650 1425);
DISPLAY INVISIBLE (2650 1425);
FORCEADD OFFPAGE..2
R 2
(2650 1475);
FORCEPROP 2 LAST $XR0 62 
J 0
(2396 1475);
DISPLAY 0.638298 (2396 1475);
PAINT MONO (2396 1475);
FORCEPROP 2 LAST CDS_LIB standard
J 0
(2650 1475);
DISPLAY INVISIBLE (2650 1475);
FORCEPROP 2 LAST PATH I269
J 0
(2700 1550);
DISPLAY 1.021277 (2700 1550);
DISPLAY INVISIBLE (2700 1550);
FORCEPROP 1 LAST OFFPAGE TRUE
J 2
(2325 1350);
DISPLAY 0.872340 (2325 1350);
PAINT AQUA (2325 1350);
DISPLAY INVISIBLE (2325 1350);
FORCEPROP 1 LAST COMMENT_BODY TRUE
J 2
(2695 1380);
DISPLAY 0.872340 (2695 1380);
PAINT GREEN (2695 1380);
DISPLAY INVISIBLE (2695 1380);
FORCEADD OFFPAGE..5
(2650 1575);
FORCEPROP 2 LAST $XR0 60 
J 0
(2396 1575);
DISPLAY 0.638298 (2396 1575);
PAINT MONO (2396 1575);
FORCEPROP 2 LAST CDS_LIB standard
J 0
(2650 1575);
DISPLAY INVISIBLE (2650 1575);
FORCEPROP 2 LAST PATH I270
J 0
(2700 1650);
DISPLAY 1.021277 (2700 1650);
DISPLAY INVISIBLE (2700 1650);
FORCEPROP 1 LAST COMMENT_BODY TRUE
J 0
(2750 1500);
DISPLAY 1.170213 (2750 1500);
PAINT GREEN (2750 1500);
DISPLAY INVISIBLE (2750 1500);
FORCEPROP 1 LAST OFFPAGE TRUE
J 0
(2975 1450);
DISPLAY 0.872340 (2975 1450);
PAINT AQUA (2975 1450);
DISPLAY INVISIBLE (2975 1450);
FORCEADD OFFPAGE..2
R 2
(2650 1625);
FORCEPROP 2 LAST $XR0 60 
J 0
(2396 1625);
DISPLAY 0.638298 (2396 1625);
PAINT MONO (2396 1625);
FORCEPROP 2 LAST CDS_LIB standard
J 0
(2650 1625);
DISPLAY INVISIBLE (2650 1625);
FORCEPROP 2 LAST PATH I271
J 0
(2700 1700);
DISPLAY 1.021277 (2700 1700);
DISPLAY INVISIBLE (2700 1700);
FORCEPROP 1 LAST OFFPAGE TRUE
J 2
(2325 1500);
DISPLAY 0.872340 (2325 1500);
PAINT AQUA (2325 1500);
DISPLAY INVISIBLE (2325 1500);
FORCEPROP 1 LAST COMMENT_BODY TRUE
J 2
(2695 1530);
DISPLAY 0.872340 (2695 1530);
PAINT GREEN (2695 1530);
DISPLAY INVISIBLE (2695 1530);
FORCEADD OFFPAGE..4
R 2
(2650 25);
FORCEPROP 2 LAST $XR0 177 
J 0
(2398 25);
DISPLAY 0.638298 (2398 25);
PAINT MONO (2398 25);
FORCEPROP 2 LAST CDS_LIB standard
J 0
(2650 25);
DISPLAY INVISIBLE (2650 25);
FORCEPROP 2 LAST PATH I272
J 0
(2700 100);
DISPLAY 1.021277 (2700 100);
DISPLAY INVISIBLE (2700 100);
FORCEPROP 1 LAST OFFPAGE TRUE
J 2
(2325 -100);
DISPLAY 0.872340 (2325 -100);
PAINT GREEN (2325 -100);
DISPLAY INVISIBLE (2325 -100);
FORCEPROP 1 LAST COMMENT_BODY TRUE
J 2
(2675 -75);
DISPLAY 0.872340 (2675 -75);
PAINT GREEN (2675 -75);
DISPLAY INVISIBLE (2675 -75);
FORCEADD OFFPAGE..4
R 2
(2650 -25);
FORCEPROP 2 LAST $XR0 177 
J 0
(2398 -25);
DISPLAY 0.638298 (2398 -25);
PAINT MONO (2398 -25);
FORCEPROP 1 LAST COMMENT_BODY TRUE
J 2
(2675 -125);
DISPLAY 0.872340 (2675 -125);
PAINT GREEN (2675 -125);
DISPLAY INVISIBLE (2675 -125);
FORCEPROP 1 LAST OFFPAGE TRUE
J 2
(2325 -150);
DISPLAY 0.872340 (2325 -150);
PAINT GREEN (2325 -150);
DISPLAY INVISIBLE (2325 -150);
FORCEPROP 2 LAST PATH I273
J 0
(2700 50);
DISPLAY 1.021277 (2700 50);
DISPLAY INVISIBLE (2700 50);
FORCEPROP 2 LAST CDS_LIB standard
J 0
(2650 -25);
DISPLAY INVISIBLE (2650 -25);
FORCEADD OFFPAGE..4
R 2
(2650 175);
FORCEPROP 2 LAST $XR0 176 
J 0
(2398 175);
DISPLAY 0.638298 (2398 175);
PAINT MONO (2398 175);
FORCEPROP 1 LAST COMMENT_BODY TRUE
J 2
(2675 75);
DISPLAY 0.872340 (2675 75);
PAINT GREEN (2675 75);
DISPLAY INVISIBLE (2675 75);
FORCEPROP 1 LAST OFFPAGE TRUE
J 2
(2325 50);
DISPLAY 0.872340 (2325 50);
PAINT GREEN (2325 50);
DISPLAY INVISIBLE (2325 50);
FORCEPROP 2 LAST PATH I274
J 0
(2700 250);
DISPLAY 1.021277 (2700 250);
DISPLAY INVISIBLE (2700 250);
FORCEPROP 2 LAST CDS_LIB standard
J 0
(2650 175);
DISPLAY INVISIBLE (2650 175);
FORCEADD OFFPAGE..4
R 2
(2650 125);
FORCEPROP 2 LAST $XR0 176 
J 0
(2398 125);
DISPLAY 0.638298 (2398 125);
PAINT MONO (2398 125);
FORCEPROP 1 LAST OFFPAGE TRUE
J 2
(2325 0);
DISPLAY 0.872340 (2325 0);
PAINT GREEN (2325 0);
DISPLAY INVISIBLE (2325 0);
FORCEPROP 1 LAST COMMENT_BODY TRUE
J 2
(2675 25);
DISPLAY 0.872340 (2675 25);
PAINT GREEN (2675 25);
DISPLAY INVISIBLE (2675 25);
FORCEPROP 2 LAST PATH I275
J 0
(2700 200);
DISPLAY 1.021277 (2700 200);
DISPLAY INVISIBLE (2700 200);
FORCEPROP 2 LAST CDS_LIB standard
J 0
(2650 125);
DISPLAY INVISIBLE (2650 125);
FORCEADD OFFPAGE..5
(2650 275);
FORCEPROP 2 LAST $XR0 62 
J 0
(2396 275);
DISPLAY 0.638298 (2396 275);
PAINT MONO (2396 275);
FORCEPROP 1 LAST COMMENT_BODY TRUE
J 0
(2750 200);
DISPLAY 1.170213 (2750 200);
PAINT GREEN (2750 200);
DISPLAY INVISIBLE (2750 200);
FORCEPROP 1 LAST OFFPAGE TRUE
J 0
(2975 150);
DISPLAY 0.872340 (2975 150);
PAINT AQUA (2975 150);
DISPLAY INVISIBLE (2975 150);
FORCEPROP 2 LAST PATH I276
J 0
(2700 350);
DISPLAY 1.021277 (2700 350);
DISPLAY INVISIBLE (2700 350);
FORCEPROP 2 LAST CDS_LIB standard
J 0
(2650 275);
DISPLAY INVISIBLE (2650 275);
FORCEADD OFFPAGE..2
R 2
(2650 325);
FORCEPROP 2 LAST $XR0 62 
J 0
(2396 325);
DISPLAY 0.638298 (2396 325);
PAINT MONO (2396 325);
FORCEPROP 2 LAST CDS_LIB standard
J 0
(2650 325);
DISPLAY INVISIBLE (2650 325);
FORCEPROP 2 LAST PATH I277
J 0
(2700 400);
DISPLAY 1.021277 (2700 400);
DISPLAY INVISIBLE (2700 400);
FORCEPROP 1 LAST OFFPAGE TRUE
J 2
(2325 200);
DISPLAY 0.872340 (2325 200);
PAINT AQUA (2325 200);
DISPLAY INVISIBLE (2325 200);
FORCEPROP 1 LAST COMMENT_BODY TRUE
J 2
(2695 230);
DISPLAY 0.872340 (2695 230);
PAINT GREEN (2695 230);
DISPLAY INVISIBLE (2695 230);
FORCEADD OFFPAGE..5
(2650 425);
FORCEPROP 2 LAST $XR0 60 
J 0
(2396 425);
DISPLAY 0.638298 (2396 425);
PAINT MONO (2396 425);
FORCEPROP 2 LAST CDS_LIB standard
J 0
(2650 425);
DISPLAY INVISIBLE (2650 425);
FORCEPROP 2 LAST PATH I278
J 0
(2700 500);
DISPLAY 1.021277 (2700 500);
DISPLAY INVISIBLE (2700 500);
FORCEPROP 1 LAST COMMENT_BODY TRUE
J 0
(2750 350);
DISPLAY 1.170213 (2750 350);
PAINT GREEN (2750 350);
DISPLAY INVISIBLE (2750 350);
FORCEPROP 1 LAST OFFPAGE TRUE
J 0
(2975 300);
DISPLAY 0.872340 (2975 300);
PAINT AQUA (2975 300);
DISPLAY INVISIBLE (2975 300);
FORCEADD OFFPAGE..2
R 2
(2650 475);
FORCEPROP 2 LAST $XR0 60 
J 0
(2396 475);
DISPLAY 0.638298 (2396 475);
PAINT MONO (2396 475);
FORCEPROP 2 LAST CDS_LIB standard
J 0
(2650 475);
DISPLAY INVISIBLE (2650 475);
FORCEPROP 2 LAST PATH I279
J 0
(2700 550);
DISPLAY 1.021277 (2700 550);
DISPLAY INVISIBLE (2700 550);
FORCEPROP 1 LAST OFFPAGE TRUE
J 2
(2325 350);
DISPLAY 0.872340 (2325 350);
PAINT AQUA (2325 350);
DISPLAY INVISIBLE (2325 350);
FORCEPROP 1 LAST COMMENT_BODY TRUE
J 2
(2695 380);
DISPLAY 0.872340 (2695 380);
PAINT GREEN (2695 380);
DISPLAY INVISIBLE (2695 380);
FORCEADD OFFPAGE..5
(2650 725);
FORCEPROP 2 LAST $XR0 148 
J 0
(2365 725);
DISPLAY 0.638298 (2365 725);
PAINT MONO (2365 725);
FORCEPROP 2 LAST CDS_LIB standard
J 0
(2650 725);
DISPLAY INVISIBLE (2650 725);
FORCEPROP 2 LAST PATH I280
J 0
(2700 800);
DISPLAY 1.021277 (2700 800);
DISPLAY INVISIBLE (2700 800);
FORCEPROP 1 LAST COMMENT_BODY TRUE
J 0
(2750 650);
DISPLAY 1.170213 (2750 650);
PAINT GREEN (2750 650);
DISPLAY INVISIBLE (2750 650);
FORCEPROP 1 LAST OFFPAGE TRUE
J 0
(2975 600);
DISPLAY 0.872340 (2975 600);
PAINT AQUA (2975 600);
DISPLAY INVISIBLE (2975 600);
FORCEADD OFFPAGE..4
R 2
(2650 1875);
FORCEPROP 2 LAST $XR0 234 
J 0
(2368 1875);
DISPLAY 0.638298 (2368 1875);
PAINT MONO (2368 1875);
FORCEPROP 2 LAST CDS_LIB standard
J 0
(2650 1875);
DISPLAY INVISIBLE (2650 1875);
FORCEPROP 2 LAST PATH I292
J 0
(2700 1950);
DISPLAY 1.021277 (2700 1950);
DISPLAY INVISIBLE (2700 1950);
FORCEPROP 1 LAST COMMENT_BODY TRUE
J 2
(2675 1775);
DISPLAY 0.872340 (2675 1775);
PAINT GREEN (2675 1775);
DISPLAY INVISIBLE (2675 1775);
FORCEPROP 1 LAST OFFPAGE TRUE
J 2
(2325 1750);
DISPLAY 0.872340 (2325 1750);
PAINT GREEN (2325 1750);
DISPLAY INVISIBLE (2325 1750);
FORCEADD OFFPAGE..3
R 2
(2650 1925);
FORCEPROP 2 LAST $XR0 234 
J 0
(2370 1925);
DISPLAY 0.638298 (2370 1925);
PAINT MONO (2370 1925);
FORCEPROP 2 LAST CDS_LIB standard
J 0
(2650 1925);
DISPLAY INVISIBLE (2650 1925);
FORCEPROP 2 LAST PATH I293
J 0
(2700 2000);
DISPLAY 1.021277 (2700 2000);
DISPLAY INVISIBLE (2700 2000);
FORCEPROP 1 LAST OFFPAGE TRUE
J 2
(2325 1800);
DISPLAY 0.872340 (2325 1800);
DISPLAY INVISIBLE (2325 1800);
FORCEPROP 1 LAST COMMENT_BODY TRUE
J 2
(2700 1825);
DISPLAY 0.872340 (2700 1825);
PAINT GREEN (2700 1825);
DISPLAY INVISIBLE (2700 1825);
FORCEADD OFFPAGE..4
R 2
(2650 3025);
FORCEPROP 2 LAST $XR0 234 
J 0
(2368 3025);
DISPLAY 0.638298 (2368 3025);
PAINT MONO (2368 3025);
FORCEPROP 2 LAST PATH I294
J 0
(2700 3100);
DISPLAY 1.021277 (2700 3100);
DISPLAY INVISIBLE (2700 3100);
FORCEPROP 1 LAST COMMENT_BODY TRUE
J 2
(2675 2925);
DISPLAY 0.872340 (2675 2925);
PAINT GREEN (2675 2925);
DISPLAY INVISIBLE (2675 2925);
FORCEPROP 1 LAST OFFPAGE TRUE
J 2
(2325 2900);
DISPLAY 0.872340 (2325 2900);
PAINT GREEN (2325 2900);
DISPLAY INVISIBLE (2325 2900);
FORCEPROP 2 LAST CDS_LIB standard
J 0
(2650 3025);
DISPLAY INVISIBLE (2650 3025);
FORCEADD OFFPAGE..3
R 2
(2650 3075);
FORCEPROP 2 LAST $XR0 234 
J 0
(2370 3075);
DISPLAY 0.638298 (2370 3075);
PAINT MONO (2370 3075);
FORCEPROP 2 LAST CDS_LIB standard
J 0
(2650 3075);
DISPLAY INVISIBLE (2650 3075);
FORCEPROP 2 LAST PATH I295
J 0
(2700 3150);
DISPLAY 1.021277 (2700 3150);
DISPLAY INVISIBLE (2700 3150);
FORCEPROP 1 LAST COMMENT_BODY TRUE
J 2
(2700 2975);
DISPLAY 0.872340 (2700 2975);
PAINT GREEN (2700 2975);
DISPLAY INVISIBLE (2700 2975);
FORCEPROP 1 LAST OFFPAGE TRUE
J 2
(2325 2950);
DISPLAY 0.872340 (2325 2950);
DISPLAY INVISIBLE (2325 2950);
FORCEADD OFFPAGE..4
R 2
(2650 2025);
FORCEPROP 2 LAST $XR0 207 
J 0
(2398 2025);
DISPLAY 0.638298 (2398 2025);
PAINT MONO (2398 2025);
FORCEPROP 1 LAST COMMENT_BODY TRUE
J 2
(2675 1925);
DISPLAY 0.872340 (2675 1925);
PAINT GREEN (2675 1925);
DISPLAY INVISIBLE (2675 1925);
FORCEPROP 1 LAST OFFPAGE TRUE
J 2
(2325 1900);
DISPLAY 0.872340 (2325 1900);
PAINT GREEN (2325 1900);
DISPLAY INVISIBLE (2325 1900);
FORCEPROP 2 LAST CDS_LIB standard
J 0
(2650 2025);
DISPLAY INVISIBLE (2650 2025);
FORCEPROP 2 LAST PATH I298
J 0
(2700 2100);
DISPLAY 1.021277 (2700 2100);
DISPLAY INVISIBLE (2700 2100);
FORCEADD OFFPAGE..4
R 2
(2650 2075);
FORCEPROP 2 LAST $XR0 207 
J 0
(2398 2075);
DISPLAY 0.638298 (2398 2075);
PAINT MONO (2398 2075);
FORCEPROP 1 LAST COMMENT_BODY TRUE
J 2
(2675 1975);
DISPLAY 0.872340 (2675 1975);
PAINT GREEN (2675 1975);
DISPLAY INVISIBLE (2675 1975);
FORCEPROP 1 LAST OFFPAGE TRUE
J 2
(2325 1950);
DISPLAY 0.872340 (2325 1950);
PAINT GREEN (2325 1950);
DISPLAY INVISIBLE (2325 1950);
FORCEPROP 2 LAST CDS_LIB standard
J 0
(2650 2075);
DISPLAY INVISIBLE (2650 2075);
FORCEPROP 2 LAST PATH I299
J 0
(2700 2150);
DISPLAY 1.021277 (2700 2150);
DISPLAY INVISIBLE (2700 2150);
FORCEADD OFFPAGE..4
R 2
(2650 -125);
FORCEPROP 2 LAST $XR0 207 
J 0
(2398 -125);
DISPLAY 0.638298 (2398 -125);
PAINT MONO (2398 -125);
FORCEPROP 2 LAST PATH I302
J 0
(2700 -50);
DISPLAY 1.021277 (2700 -50);
DISPLAY INVISIBLE (2700 -50);
FORCEPROP 2 LAST CDS_LIB standard
J 0
(2650 -125);
DISPLAY INVISIBLE (2650 -125);
FORCEPROP 1 LAST OFFPAGE TRUE
J 2
(2325 -250);
DISPLAY 0.872340 (2325 -250);
PAINT GREEN (2325 -250);
DISPLAY INVISIBLE (2325 -250);
FORCEPROP 1 LAST COMMENT_BODY TRUE
J 2
(2675 -225);
DISPLAY 0.872340 (2675 -225);
PAINT GREEN (2675 -225);
DISPLAY INVISIBLE (2675 -225);
FORCEADD OFFPAGE..4
R 2
(2650 -325);
FORCEPROP 2 LAST $XR0 152 
J 0
(2398 -325);
DISPLAY 0.638298 (2398 -325);
PAINT MONO (2398 -325);
FORCEPROP 2 LAST CDS_LIB standard
J 0
(2650 -325);
DISPLAY INVISIBLE (2650 -325);
FORCEPROP 2 LAST PATH I304
J 0
(2700 -250);
DISPLAY 1.021277 (2700 -250);
DISPLAY INVISIBLE (2700 -250);
FORCEPROP 1 LAST COMMENT_BODY TRUE
J 2
(2675 -425);
DISPLAY 0.872340 (2675 -425);
PAINT GREEN (2675 -425);
DISPLAY INVISIBLE (2675 -425);
FORCEPROP 1 LAST OFFPAGE TRUE
J 2
(2325 -450);
DISPLAY 0.872340 (2325 -450);
PAINT GREEN (2325 -450);
DISPLAY INVISIBLE (2325 -450);
FORCEADD OFFPAGE..4
R 2
(2650 -275);
FORCEPROP 2 LAST $XR0 152 
J 0
(2398 -275);
DISPLAY 0.638298 (2398 -275);
PAINT MONO (2398 -275);
FORCEPROP 2 LAST CDS_LIB standard
J 0
(2650 -275);
DISPLAY INVISIBLE (2650 -275);
FORCEPROP 2 LAST PATH I305
J 0
(2700 -200);
DISPLAY 1.021277 (2700 -200);
DISPLAY INVISIBLE (2700 -200);
FORCEPROP 1 LAST OFFPAGE TRUE
J 2
(2325 -400);
DISPLAY 0.872340 (2325 -400);
PAINT GREEN (2325 -400);
DISPLAY INVISIBLE (2325 -400);
FORCEPROP 1 LAST COMMENT_BODY TRUE
J 2
(2675 -375);
DISPLAY 0.872340 (2675 -375);
PAINT GREEN (2675 -375);
DISPLAY INVISIBLE (2675 -375);
FORCEADD OFFPAGE..4
R 2
(-1975 750);
FORCEPROP 2 LAST $XR0 167 
J 0
(-2227 750);
DISPLAY 0.638298 (-2227 750);
PAINT MONO (-2227 750);
FORCEPROP 2 LAST CDS_LIB standard
J 0
(-1975 750);
DISPLAY INVISIBLE (-1975 750);
FORCEPROP 2 LAST PATH I310
J 0
(-1925 825);
DISPLAY 1.021277 (-1925 825);
DISPLAY INVISIBLE (-1925 825);
FORCEPROP 1 LAST OFFPAGE TRUE
J 2
(-2300 625);
DISPLAY 0.872340 (-2300 625);
PAINT GREEN (-2300 625);
DISPLAY INVISIBLE (-2300 625);
FORCEPROP 1 LAST COMMENT_BODY TRUE
J 2
(-1950 650);
DISPLAY 0.872340 (-1950 650);
PAINT GREEN (-1950 650);
DISPLAY INVISIBLE (-1950 650);
FORCEADD OFFPAGE..4
R 2
(-1975 800);
FORCEPROP 2 LAST $XR0 167 
J 0
(-2227 800);
DISPLAY 0.638298 (-2227 800);
PAINT MONO (-2227 800);
FORCEPROP 2 LAST CDS_LIB standard
J 0
(-1975 800);
DISPLAY INVISIBLE (-1975 800);
FORCEPROP 2 LAST PATH I311
J 0
(-1925 875);
DISPLAY 1.021277 (-1925 875);
DISPLAY INVISIBLE (-1925 875);
FORCEPROP 1 LAST OFFPAGE TRUE
J 2
(-2300 675);
DISPLAY 0.872340 (-2300 675);
PAINT GREEN (-2300 675);
DISPLAY INVISIBLE (-2300 675);
FORCEPROP 1 LAST COMMENT_BODY TRUE
J 2
(-1950 700);
DISPLAY 0.872340 (-1950 700);
PAINT GREEN (-1950 700);
DISPLAY INVISIBLE (-1950 700);
FORCEADD OFFPAGE..5
(-1975 900);
FORCEPROP 2 LAST $XR0 167 
J 0
(-2230 900);
DISPLAY 0.638298 (-2230 900);
PAINT MONO (-2230 900);
FORCEPROP 1 LAST OFFPAGE TRUE
J 0
(-1650 775);
DISPLAY 0.872340 (-1650 775);
PAINT AQUA (-1650 775);
DISPLAY INVISIBLE (-1650 775);
FORCEPROP 1 LAST COMMENT_BODY TRUE
J 0
(-1875 825);
DISPLAY 1.170213 (-1875 825);
PAINT GREEN (-1875 825);
DISPLAY INVISIBLE (-1875 825);
FORCEPROP 2 LAST PATH I312
J 0
(-1925 975);
DISPLAY 1.021277 (-1925 975);
DISPLAY INVISIBLE (-1925 975);
FORCEPROP 2 LAST CDS_LIB standard
J 0
(-1975 900);
DISPLAY INVISIBLE (-1975 900);
FORCEADD OFFPAGE..2
R 2
(-1975 950);
FORCEPROP 2 LAST $XR0 167 
J 0
(-2230 950);
DISPLAY 0.638298 (-2230 950);
PAINT MONO (-2230 950);
FORCEPROP 2 LAST CDS_LIB standard
J 0
(-1975 950);
DISPLAY INVISIBLE (-1975 950);
FORCEPROP 2 LAST PATH I313
J 0
(-1925 1025);
DISPLAY 1.021277 (-1925 1025);
DISPLAY INVISIBLE (-1925 1025);
FORCEPROP 1 LAST OFFPAGE TRUE
J 2
(-2300 825);
DISPLAY 0.872340 (-2300 825);
PAINT AQUA (-2300 825);
DISPLAY INVISIBLE (-2300 825);
FORCEPROP 1 LAST COMMENT_BODY TRUE
J 2
(-1930 855);
DISPLAY 0.872340 (-1930 855);
PAINT GREEN (-1930 855);
DISPLAY INVISIBLE (-1930 855);
FORCEADD OFFPAGE..4
R 2
(2650 875);
FORCEPROP 2 LAST $XR0 212 
J 0
(2398 875);
DISPLAY 0.638298 (2398 875);
PAINT MONO (2398 875);
FORCEPROP 2 LAST PATH I318
J 0
(2400 925);
DISPLAY 1.021277 (2400 925);
DISPLAY INVISIBLE (2400 925);
FORCEPROP 2 LAST CDS_LIB standard
J 0
(2650 875);
DISPLAY INVISIBLE (2650 875);
FORCEPROP 1 LAST OFFPAGE TRUE
J 2
(2325 750);
DISPLAY 0.872340 (2325 750);
PAINT GREEN (2325 750);
DISPLAY INVISIBLE (2325 750);
FORCEPROP 1 LAST COMMENT_BODY TRUE
J 2
(2675 775);
DISPLAY 0.872340 (2675 775);
PAINT GREEN (2675 775);
DISPLAY INVISIBLE (2675 775);
FORCEADD OFFPAGE..4
R 2
(2650 825);
FORCEPROP 2 LAST $XR0 212 
J 0
(2398 825);
DISPLAY 0.638298 (2398 825);
PAINT MONO (2398 825);
FORCEPROP 2 LAST PATH I319
J 0
(2400 875);
DISPLAY 1.021277 (2400 875);
DISPLAY INVISIBLE (2400 875);
FORCEPROP 2 LAST CDS_LIB standard
J 0
(2650 825);
DISPLAY INVISIBLE (2650 825);
FORCEPROP 1 LAST OFFPAGE TRUE
J 2
(2325 700);
DISPLAY 0.872340 (2325 700);
PAINT GREEN (2325 700);
DISPLAY INVISIBLE (2325 700);
FORCEPROP 1 LAST COMMENT_BODY TRUE
J 2
(2675 725);
DISPLAY 0.872340 (2675 725);
PAINT GREEN (2675 725);
DISPLAY INVISIBLE (2675 725);
FORCEADD OFFPAGE..4
R 2
(-2000 3100);
FORCEPROP 2 LAST $XR0 181 
J 0
(-2252 3100);
DISPLAY 0.638298 (-2252 3100);
PAINT MONO (-2252 3100);
FORCEPROP 2 LAST PATH I336
J 0
(-2250 3150);
DISPLAY 1.021277 (-2250 3150);
DISPLAY INVISIBLE (-2250 3150);
FORCEPROP 2 LAST CDS_LIB standard
J 0
(-2000 3100);
DISPLAY INVISIBLE (-2000 3100);
FORCEPROP 1 LAST OFFPAGE TRUE
J 2
(-2325 2975);
DISPLAY 0.872340 (-2325 2975);
PAINT GREEN (-2325 2975);
DISPLAY INVISIBLE (-2325 2975);
FORCEPROP 1 LAST COMMENT_BODY TRUE
J 2
(-1975 3000);
DISPLAY 0.872340 (-1975 3000);
PAINT GREEN (-1975 3000);
DISPLAY INVISIBLE (-1975 3000);
FORCEADD OFFPAGE..4
R 2
(-2000 3150);
FORCEPROP 2 LAST $XR0 181 
J 0
(-2252 3150);
DISPLAY 0.638298 (-2252 3150);
PAINT MONO (-2252 3150);
FORCEPROP 2 LAST PATH I337
J 0
(-2250 3200);
DISPLAY 1.021277 (-2250 3200);
DISPLAY INVISIBLE (-2250 3200);
FORCEPROP 2 LAST CDS_LIB standard
J 0
(-2000 3150);
DISPLAY INVISIBLE (-2000 3150);
FORCEPROP 1 LAST COMMENT_BODY TRUE
J 2
(-1975 3050);
DISPLAY 0.872340 (-1975 3050);
PAINT GREEN (-1975 3050);
DISPLAY INVISIBLE (-1975 3050);
FORCEPROP 1 LAST OFFPAGE TRUE
J 2
(-2325 3025);
DISPLAY 0.872340 (-2325 3025);
PAINT GREEN (-2325 3025);
DISPLAY INVISIBLE (-2325 3025);
FORCEADD OFFPAGE..4
R 2
(-2000 3000);
FORCEPROP 2 LAST $XR0 181 
J 0
(-2252 3000);
DISPLAY 0.638298 (-2252 3000);
PAINT MONO (-2252 3000);
FORCEPROP 2 LAST PATH I338
J 0
(-2250 3050);
DISPLAY 1.021277 (-2250 3050);
DISPLAY INVISIBLE (-2250 3050);
FORCEPROP 2 LAST CDS_LIB standard
J 0
(-2000 3000);
DISPLAY INVISIBLE (-2000 3000);
FORCEPROP 1 LAST COMMENT_BODY TRUE
J 2
(-1975 2900);
DISPLAY 0.872340 (-1975 2900);
PAINT GREEN (-1975 2900);
DISPLAY INVISIBLE (-1975 2900);
FORCEPROP 1 LAST OFFPAGE TRUE
J 2
(-2325 2875);
DISPLAY 0.872340 (-2325 2875);
PAINT GREEN (-2325 2875);
DISPLAY INVISIBLE (-2325 2875);
FORCEADD OFFPAGE..4
R 2
(-2000 2950);
FORCEPROP 2 LAST $XR0 181 
J 0
(-2252 2950);
DISPLAY 0.638298 (-2252 2950);
PAINT MONO (-2252 2950);
FORCEPROP 2 LAST PATH I339
J 0
(-2250 3000);
DISPLAY 1.021277 (-2250 3000);
DISPLAY INVISIBLE (-2250 3000);
FORCEPROP 1 LAST OFFPAGE TRUE
J 2
(-2325 2825);
DISPLAY 0.872340 (-2325 2825);
PAINT GREEN (-2325 2825);
DISPLAY INVISIBLE (-2325 2825);
FORCEPROP 1 LAST COMMENT_BODY TRUE
J 2
(-1975 2850);
DISPLAY 0.872340 (-1975 2850);
PAINT GREEN (-1975 2850);
DISPLAY INVISIBLE (-1975 2850);
FORCEPROP 2 LAST CDS_LIB standard
J 0
(-2000 2950);
DISPLAY INVISIBLE (-2000 2950);
FORCEADD OFFPAGE..4
R 2
(-2000 2000);
FORCEPROP 2 LAST $XR0 181 
J 0
(-2252 2000);
DISPLAY 0.638298 (-2252 2000);
PAINT MONO (-2252 2000);
FORCEPROP 1 LAST OFFPAGE TRUE
J 2
(-2325 1875);
DISPLAY 0.872340 (-2325 1875);
PAINT GREEN (-2325 1875);
DISPLAY INVISIBLE (-2325 1875);
FORCEPROP 1 LAST COMMENT_BODY TRUE
J 2
(-1975 1900);
DISPLAY 0.872340 (-1975 1900);
PAINT GREEN (-1975 1900);
DISPLAY INVISIBLE (-1975 1900);
FORCEPROP 2 LAST CDS_LIB standard
J 0
(-2000 2000);
DISPLAY INVISIBLE (-2000 2000);
FORCEPROP 2 LAST PATH I340
J 0
(-2250 2050);
DISPLAY 1.021277 (-2250 2050);
DISPLAY INVISIBLE (-2250 2050);
FORCEADD OFFPAGE..4
R 2
(-2000 1800);
FORCEPROP 2 LAST $XR0 181 
J 0
(-2252 1800);
DISPLAY 0.638298 (-2252 1800);
PAINT MONO (-2252 1800);
FORCEPROP 1 LAST OFFPAGE TRUE
J 2
(-2325 1675);
DISPLAY 0.872340 (-2325 1675);
PAINT GREEN (-2325 1675);
DISPLAY INVISIBLE (-2325 1675);
FORCEPROP 1 LAST COMMENT_BODY TRUE
J 2
(-1975 1700);
DISPLAY 0.872340 (-1975 1700);
PAINT GREEN (-1975 1700);
DISPLAY INVISIBLE (-1975 1700);
FORCEPROP 2 LAST CDS_LIB standard
J 0
(-2000 1800);
DISPLAY INVISIBLE (-2000 1800);
FORCEPROP 2 LAST PATH I341
J 0
(-2250 1850);
DISPLAY 1.021277 (-2250 1850);
DISPLAY INVISIBLE (-2250 1850);
FORCEADD OFFPAGE..4
R 2
(-2000 1850);
FORCEPROP 2 LAST $XR0 181 
J 0
(-2252 1850);
DISPLAY 0.638298 (-2252 1850);
PAINT MONO (-2252 1850);
FORCEPROP 1 LAST OFFPAGE TRUE
J 2
(-2325 1725);
DISPLAY 0.872340 (-2325 1725);
PAINT GREEN (-2325 1725);
DISPLAY INVISIBLE (-2325 1725);
FORCEPROP 1 LAST COMMENT_BODY TRUE
J 2
(-1975 1750);
DISPLAY 0.872340 (-1975 1750);
PAINT GREEN (-1975 1750);
DISPLAY INVISIBLE (-1975 1750);
FORCEPROP 2 LAST CDS_LIB standard
J 0
(-2000 1850);
DISPLAY INVISIBLE (-2000 1850);
FORCEPROP 2 LAST PATH I342
J 0
(-2250 1900);
DISPLAY 1.021277 (-2250 1900);
DISPLAY INVISIBLE (-2250 1900);
FORCEADD OFFPAGE..4
R 2
(-2000 1950);
FORCEPROP 2 LAST $XR0 181 
J 0
(-2252 1950);
DISPLAY 0.638298 (-2252 1950);
PAINT MONO (-2252 1950);
FORCEPROP 1 LAST COMMENT_BODY TRUE
J 2
(-1975 1850);
DISPLAY 0.872340 (-1975 1850);
PAINT GREEN (-1975 1850);
DISPLAY INVISIBLE (-1975 1850);
FORCEPROP 1 LAST OFFPAGE TRUE
J 2
(-2325 1825);
DISPLAY 0.872340 (-2325 1825);
PAINT GREEN (-2325 1825);
DISPLAY INVISIBLE (-2325 1825);
FORCEPROP 2 LAST CDS_LIB standard
J 0
(-2000 1950);
DISPLAY INVISIBLE (-2000 1950);
FORCEPROP 2 LAST PATH I343
J 0
(-2250 2000);
DISPLAY 1.021277 (-2250 2000);
DISPLAY INVISIBLE (-2250 2000);
FORCEADD OFFPAGE..4
R 2
(-2000 2850);
FORCEPROP 2 LAST $XR0 149 
J 0
(-2252 2850);
DISPLAY 0.638298 (-2252 2850);
PAINT MONO (-2252 2850);
FORCEPROP 2 LAST PATH I344
J 0
(-2250 2900);
DISPLAY 1.021277 (-2250 2900);
DISPLAY INVISIBLE (-2250 2900);
FORCEPROP 2 LAST CDS_LIB standard
J 0
(-2000 2850);
DISPLAY INVISIBLE (-2000 2850);
FORCEPROP 1 LAST COMMENT_BODY TRUE
J 2
(-1975 2750);
DISPLAY 0.872340 (-1975 2750);
PAINT GREEN (-1975 2750);
DISPLAY INVISIBLE (-1975 2750);
FORCEPROP 1 LAST OFFPAGE TRUE
J 2
(-2325 2725);
DISPLAY 0.872340 (-2325 2725);
PAINT GREEN (-2325 2725);
DISPLAY INVISIBLE (-2325 2725);
FORCEADD OFFPAGE..4
R 2
(-1975 500);
FORCEPROP 2 LAST $XR0 149 
J 0
(-2227 500);
DISPLAY 0.638298 (-2227 500);
PAINT MONO (-2227 500);
FORCEPROP 2 LAST PATH I345
J 0
(-2225 550);
DISPLAY 1.021277 (-2225 550);
DISPLAY INVISIBLE (-2225 550);
FORCEPROP 1 LAST OFFPAGE TRUE
J 2
(-2300 375);
DISPLAY 0.872340 (-2300 375);
PAINT GREEN (-2300 375);
DISPLAY INVISIBLE (-2300 375);
FORCEPROP 1 LAST COMMENT_BODY TRUE
J 2
(-1950 400);
DISPLAY 0.872340 (-1950 400);
PAINT GREEN (-1950 400);
DISPLAY INVISIBLE (-1950 400);
FORCEPROP 2 LAST CDS_LIB standard
J 0
(-1975 500);
DISPLAY INVISIBLE (-1975 500);
FORCEADD OFFPAGE..4
R 2
(2650 575);
FORCEPROP 2 LAST $XR0 149 
J 0
(2398 575);
DISPLAY 0.638298 (2398 575);
PAINT MONO (2398 575);
FORCEPROP 2 LAST CDS_LIB standard
J 0
(2650 575);
DISPLAY INVISIBLE (2650 575);
FORCEPROP 1 LAST COMMENT_BODY TRUE
J 2
(2675 475);
DISPLAY 0.872340 (2675 475);
PAINT GREEN (2675 475);
DISPLAY INVISIBLE (2675 475);
FORCEPROP 1 LAST OFFPAGE TRUE
J 2
(2325 450);
DISPLAY 0.872340 (2325 450);
PAINT GREEN (2325 450);
DISPLAY INVISIBLE (2325 450);
FORCEPROP 2 LAST PATH I346
J 0
(2400 625);
DISPLAY 1.021277 (2400 625);
DISPLAY INVISIBLE (2400 625);
FORCEADD OFFPAGE..4
R 2
(2650 2925);
FORCEPROP 2 LAST $XR0 150 
J 0
(2398 2925);
DISPLAY 0.638298 (2398 2925);
PAINT MONO (2398 2925);
FORCEPROP 2 LAST CDS_LIB standard
J 0
(2650 2925);
DISPLAY INVISIBLE (2650 2925);
FORCEPROP 1 LAST OFFPAGE TRUE
J 2
(2325 2800);
DISPLAY 0.872340 (2325 2800);
PAINT GREEN (2325 2800);
DISPLAY INVISIBLE (2325 2800);
FORCEPROP 1 LAST COMMENT_BODY TRUE
J 2
(2675 2825);
DISPLAY 0.872340 (2675 2825);
PAINT GREEN (2675 2825);
DISPLAY INVISIBLE (2675 2825);
FORCEPROP 2 LAST PATH I347
J 0
(2375 2975);
DISPLAY 1.021277 (2375 2975);
DISPLAY INVISIBLE (2375 2975);
FORCEADD OFFPAGE..5
(-1975 650);
FORCEPROP 2 LAST $XR0 147 
J 0
(-2230 650);
DISPLAY 0.638298 (-2230 650);
PAINT MONO (-2230 650);
FORCEPROP 2 LAST CDS_LIB standard
J 0
(-1975 650);
DISPLAY INVISIBLE (-1975 650);
FORCEPROP 2 LAST PATH I348
J 0
(-1925 725);
DISPLAY 1.021277 (-1925 725);
DISPLAY INVISIBLE (-1925 725);
FORCEPROP 1 LAST COMMENT_BODY TRUE
J 0
(-1875 575);
DISPLAY 1.170213 (-1875 575);
PAINT GREEN (-1875 575);
DISPLAY INVISIBLE (-1875 575);
FORCEPROP 1 LAST OFFPAGE TRUE
J 0
(-1650 525);
DISPLAY 0.872340 (-1650 525);
PAINT AQUA (-1650 525);
DISPLAY INVISIBLE (-1650 525);
FORCEADD OFFPAGE..4
R 2
(2650 2775);
FORCEPROP 2 LAST $XR1 145 
J 0
(2278 2775);
DISPLAY 0.638298 (2278 2775);
PAINT MONO (2278 2775);
FORCEPROP 2 LAST $XR0 144 
J 0
(2398 2775);
DISPLAY 0.638298 (2398 2775);
PAINT MONO (2398 2775);
FORCEPROP 2 LAST PATH I349
J 0
(2700 2850);
DISPLAY 1.021277 (2700 2850);
DISPLAY INVISIBLE (2700 2850);
FORCEPROP 1 LAST COMMENT_BODY TRUE
J 2
(2675 2675);
DISPLAY 0.872340 (2675 2675);
PAINT GREEN (2675 2675);
DISPLAY INVISIBLE (2675 2675);
FORCEPROP 1 LAST OFFPAGE TRUE
J 2
(2325 2650);
DISPLAY 0.872340 (2325 2650);
PAINT GREEN (2325 2650);
DISPLAY INVISIBLE (2325 2650);
FORCEPROP 2 LAST CDS_LIB standard
J 0
(2650 2775);
DISPLAY INVISIBLE (2650 2775);
FORCEADD OFFPAGE..2
R 2
(-2000 2700);
FORCEPROP 2 LAST $XR0 144 
J 0
(-2255 2700);
DISPLAY 0.638298 (-2255 2700);
PAINT MONO (-2255 2700);
FORCEPROP 1 LAST COMMENT_BODY TRUE
J 2
(-1955 2605);
DISPLAY 0.872340 (-1955 2605);
PAINT GREEN (-1955 2605);
DISPLAY INVISIBLE (-1955 2605);
FORCEPROP 1 LAST OFFPAGE TRUE
J 2
(-2325 2575);
DISPLAY 0.872340 (-2325 2575);
PAINT AQUA (-2325 2575);
DISPLAY INVISIBLE (-2325 2575);
FORCEPROP 2 LAST PATH I350
J 0
(-1950 2775);
DISPLAY 1.021277 (-1950 2775);
DISPLAY INVISIBLE (-1950 2775);
FORCEPROP 2 LAST CDS_LIB standard
J 0
(-2000 2700);
DISPLAY INVISIBLE (-2000 2700);
FORCEADD OFFPAGE..4
R 2
(2650 -175);
FORCEPROP 2 LAST $XR0 207 
J 0
(2398 -175);
DISPLAY 0.638298 (2398 -175);
PAINT MONO (2398 -175);
FORCEPROP 1 LAST COMMENT_BODY TRUE
J 2
(2675 -275);
DISPLAY 0.872340 (2675 -275);
PAINT GREEN (2675 -275);
DISPLAY INVISIBLE (2675 -275);
FORCEPROP 1 LAST OFFPAGE TRUE
J 2
(2325 -300);
DISPLAY 0.872340 (2325 -300);
PAINT GREEN (2325 -300);
DISPLAY INVISIBLE (2325 -300);
FORCEPROP 2 LAST CDS_LIB standard
J 0
(2650 -175);
DISPLAY INVISIBLE (2650 -175);
FORCEPROP 2 LAST PATH I351
J 0
(2400 -125);
DISPLAY 1.021277 (2400 -125);
DISPLAY INVISIBLE (2400 -125);
FORCEADD OFFPAGE..4
R 2
(2650 3225);
FORCEPROP 2 LAST $XR0 207 
J 0
(2398 3225);
DISPLAY 0.638298 (2398 3225);
PAINT MONO (2398 3225);
FORCEPROP 1 LAST OFFPAGE TRUE
J 2
(2325 3100);
DISPLAY 0.872340 (2325 3100);
PAINT GREEN (2325 3100);
DISPLAY INVISIBLE (2325 3100);
FORCEPROP 1 LAST COMMENT_BODY TRUE
J 2
(2675 3125);
DISPLAY 0.872340 (2675 3125);
PAINT GREEN (2675 3125);
DISPLAY INVISIBLE (2675 3125);
FORCEPROP 2 LAST PATH I352
J 0
(2700 3300);
DISPLAY 1.021277 (2700 3300);
DISPLAY INVISIBLE (2700 3300);
FORCEPROP 2 LAST CDS_LIB standard
J 0
(2650 3225);
DISPLAY INVISIBLE (2650 3225);
FORCEADD OFFPAGE..4
R 2
(2650 3175);
FORCEPROP 2 LAST $XR0 207 
J 0
(2398 3175);
DISPLAY 0.638298 (2398 3175);
PAINT MONO (2398 3175);
FORCEPROP 1 LAST OFFPAGE TRUE
J 2
(2325 3050);
DISPLAY 0.872340 (2325 3050);
PAINT GREEN (2325 3050);
DISPLAY INVISIBLE (2325 3050);
FORCEPROP 1 LAST COMMENT_BODY TRUE
J 2
(2675 3075);
DISPLAY 0.872340 (2675 3075);
PAINT GREEN (2675 3075);
DISPLAY INVISIBLE (2675 3075);
FORCEPROP 2 LAST PATH I353
J 0
(2700 3250);
DISPLAY 1.021277 (2700 3250);
DISPLAY INVISIBLE (2700 3250);
FORCEPROP 2 LAST CDS_LIB standard
J 0
(2650 3175);
DISPLAY INVISIBLE (2650 3175);
FORCEADD CONN160_10131762101LF..1
(600 1675);
FORCEPROP 1 LAST PART_NUMBER DFHSG0FR007
J 0
(-450 4000);
DISPLAY 0.723404 (-450 4000);
PAINT GREEN (-450 4000);
DISPLAY INVISIBLE (-450 4000);
FORCEPROP 1 LAST MATERIAL IO
J 0
(-450 3950);
DISPLAY 0.723404 (-450 3950);
PAINT GREEN (-450 3950);
FORCEPROP 2 LAST PART_TYPE THLF
J 0
(-450 4100);
DISPLAY 1.021277 (-450 4100);
FORCEPROP 1 LAST LOCATION J112
J 0
(-450 4050);
DISPLAY 0.723404 (-450 4050);
PAINT GREEN (-450 4050);
FORCEPROP 0 LASTPIN (-625 500) $PN A5
J 2
(-635 510);
DISPLAY 0.680851 (-635 510);
PAINT MONO (-635 510);
FORCEPROP 0 LASTPIN (-625 1600) $PN A6
J 2
(-635 1610);
DISPLAY 0.680851 (-635 1610);
PAINT MONO (-635 1610);
FORCEPROP 0 LASTPIN (-625 2700) $PN A7
J 2
(-635 2710);
DISPLAY 0.680851 (-635 2710);
PAINT MONO (-635 2710);
FORCEPROP 0 LASTPIN (-625 3800) $PN A8
J 2
(-635 3810);
DISPLAY 0.680851 (-635 3810);
PAINT MONO (-635 3810);
FORCEPROP 0 LASTPIN (-625 450) $PN B5
J 2
(-635 460);
DISPLAY 0.680851 (-635 460);
PAINT MONO (-635 460);
FORCEPROP 0 LASTPIN (-625 1550) $PN B6
J 2
(-635 1560);
DISPLAY 0.680851 (-635 1560);
PAINT MONO (-635 1560);
FORCEPROP 0 LASTPIN (-625 2650) $PN B7
J 2
(-635 2660);
DISPLAY 0.680851 (-635 2660);
PAINT MONO (-635 2660);
FORCEPROP 0 LASTPIN (-625 3750) $PN B8
J 2
(-635 3760);
DISPLAY 0.680851 (-635 3760);
PAINT MONO (-635 3760);
FORCEPROP 0 LASTPIN (-625 400) $PN C5
J 2
(-635 410);
DISPLAY 0.680851 (-635 410);
PAINT MONO (-635 410);
FORCEPROP 0 LASTPIN (-625 1500) $PN C6
J 2
(-635 1510);
DISPLAY 0.680851 (-635 1510);
PAINT MONO (-635 1510);
FORCEPROP 0 LASTPIN (-625 2600) $PN C7
J 2
(-635 2610);
DISPLAY 0.680851 (-635 2610);
PAINT MONO (-635 2610);
FORCEPROP 0 LASTPIN (-625 3700) $PN C8
J 2
(-635 3710);
DISPLAY 0.680851 (-635 3710);
PAINT MONO (-635 3710);
FORCEPROP 0 LASTPIN (-625 350) $PN D5
J 2
(-635 360);
DISPLAY 0.680851 (-635 360);
PAINT MONO (-635 360);
FORCEPROP 0 LASTPIN (-625 1450) $PN D6
J 2
(-635 1460);
DISPLAY 0.680851 (-635 1460);
PAINT MONO (-635 1460);
FORCEPROP 0 LASTPIN (-625 2550) $PN D7
J 2
(-635 2560);
DISPLAY 0.680851 (-635 2560);
PAINT MONO (-635 2560);
FORCEPROP 0 LASTPIN (-625 3650) $PN D8
J 2
(-635 3660);
DISPLAY 0.680851 (-635 3660);
PAINT MONO (-635 3660);
FORCEPROP 0 LASTPIN (-625 300) $PN E5
J 2
(-635 310);
DISPLAY 0.680851 (-635 310);
PAINT MONO (-635 310);
FORCEPROP 0 LASTPIN (-625 1400) $PN E6
J 2
(-635 1410);
DISPLAY 0.680851 (-635 1410);
PAINT MONO (-635 1410);
FORCEPROP 0 LASTPIN (-625 2500) $PN E7
J 2
(-635 2510);
DISPLAY 0.680851 (-635 2510);
PAINT MONO (-635 2510);
FORCEPROP 0 LASTPIN (-625 3600) $PN E8
J 2
(-635 3610);
DISPLAY 0.680851 (-635 3610);
PAINT MONO (-635 3610);
FORCEPROP 0 LASTPIN (-625 250) $PN F5
J 2
(-635 260);
DISPLAY 0.680851 (-635 260);
PAINT MONO (-635 260);
FORCEPROP 0 LASTPIN (-625 1350) $PN F6
J 2
(-635 1360);
DISPLAY 0.680851 (-635 1360);
PAINT MONO (-635 1360);
FORCEPROP 0 LASTPIN (-625 2450) $PN F7
J 2
(-635 2460);
DISPLAY 0.680851 (-635 2460);
PAINT MONO (-635 2460);
FORCEPROP 0 LASTPIN (-625 3550) $PN F8
J 2
(-635 3560);
DISPLAY 0.680851 (-635 3560);
PAINT MONO (-635 3560);
FORCEPROP 0 LASTPIN (-625 200) $PN G5
J 2
(-635 210);
DISPLAY 0.680851 (-635 210);
PAINT MONO (-635 210);
FORCEPROP 0 LASTPIN (-625 1300) $PN G6
J 2
(-635 1310);
DISPLAY 0.680851 (-635 1310);
PAINT MONO (-635 1310);
FORCEPROP 0 LASTPIN (-625 2400) $PN G7
J 2
(-635 2410);
DISPLAY 0.680851 (-635 2410);
PAINT MONO (-635 2410);
FORCEPROP 0 LASTPIN (-625 3500) $PN G8
J 2
(-635 3510);
DISPLAY 0.680851 (-635 3510);
PAINT MONO (-635 3510);
FORCEPROP 0 LASTPIN (-625 150) $PN H5
J 2
(-635 160);
DISPLAY 0.680851 (-635 160);
PAINT MONO (-635 160);
FORCEPROP 0 LASTPIN (-625 1250) $PN H6
J 2
(-635 1260);
DISPLAY 0.680851 (-635 1260);
PAINT MONO (-635 1260);
FORCEPROP 0 LASTPIN (-625 2350) $PN H7
J 2
(-635 2360);
DISPLAY 0.680851 (-635 2360);
PAINT MONO (-635 2360);
FORCEPROP 0 LASTPIN (-625 3450) $PN H8
J 2
(-635 3460);
DISPLAY 0.680851 (-635 3460);
PAINT MONO (-635 3460);
FORCEPROP 0 LASTPIN (-625 100) $PN I5
J 2
(-635 110);
DISPLAY 0.680851 (-635 110);
PAINT MONO (-635 110);
FORCEPROP 0 LASTPIN (-625 1200) $PN I6
J 2
(-635 1210);
DISPLAY 0.680851 (-635 1210);
PAINT MONO (-635 1210);
FORCEPROP 0 LASTPIN (-625 2300) $PN I7
J 2
(-635 2310);
DISPLAY 0.680851 (-635 2310);
PAINT MONO (-635 2310);
FORCEPROP 0 LASTPIN (-625 3400) $PN I8
J 2
(-635 3410);
DISPLAY 0.680851 (-635 3410);
PAINT MONO (-635 3410);
FORCEPROP 0 LASTPIN (-625 50) $PN J5
J 2
(-635 60);
DISPLAY 0.680851 (-635 60);
PAINT MONO (-635 60);
FORCEPROP 0 LASTPIN (-625 1150) $PN J6
J 2
(-635 1160);
DISPLAY 0.680851 (-635 1160);
PAINT MONO (-635 1160);
FORCEPROP 0 LASTPIN (-625 2250) $PN J7
J 2
(-635 2260);
DISPLAY 0.680851 (-635 2260);
PAINT MONO (-635 2260);
FORCEPROP 0 LASTPIN (-625 3350) $PN J8
J 2
(-635 3360);
DISPLAY 0.680851 (-635 3360);
PAINT MONO (-635 3360);
FORCEPROP 0 LASTPIN (-625 0) $PN K5
J 2
(-635 10);
DISPLAY 0.680851 (-635 10);
PAINT MONO (-635 10);
FORCEPROP 0 LASTPIN (-625 1100) $PN K6
J 2
(-635 1110);
DISPLAY 0.680851 (-635 1110);
PAINT MONO (-635 1110);
FORCEPROP 0 LASTPIN (-625 2200) $PN K7
J 2
(-635 2210);
DISPLAY 0.680851 (-635 2210);
PAINT MONO (-635 2210);
FORCEPROP 0 LASTPIN (-625 3300) $PN K8
J 2
(-635 3310);
DISPLAY 0.680851 (-635 3310);
PAINT MONO (-635 3310);
FORCEPROP 0 LASTPIN (-625 -50) $PN L5
J 2
(-635 -40);
DISPLAY 0.680851 (-635 -40);
PAINT MONO (-635 -40);
FORCEPROP 0 LASTPIN (-625 1050) $PN L6
J 2
(-635 1060);
DISPLAY 0.680851 (-635 1060);
PAINT MONO (-635 1060);
FORCEPROP 0 LASTPIN (-625 2150) $PN L7
J 2
(-635 2160);
DISPLAY 0.680851 (-635 2160);
PAINT MONO (-635 2160);
FORCEPROP 0 LASTPIN (-625 3250) $PN L8
J 2
(-635 3260);
DISPLAY 0.680851 (-635 3260);
PAINT MONO (-635 3260);
FORCEPROP 0 LASTPIN (-625 -100) $PN M5
J 2
(-635 -90);
DISPLAY 0.680851 (-635 -90);
PAINT MONO (-635 -90);
FORCEPROP 0 LASTPIN (-625 1000) $PN M6
J 2
(-635 1010);
DISPLAY 0.680851 (-635 1010);
PAINT MONO (-635 1010);
FORCEPROP 0 LASTPIN (-625 2100) $PN M7
J 2
(-635 2110);
DISPLAY 0.680851 (-635 2110);
PAINT MONO (-635 2110);
FORCEPROP 0 LASTPIN (-625 3200) $PN M8
J 2
(-635 3210);
DISPLAY 0.680851 (-635 3210);
PAINT MONO (-635 3210);
FORCEPROP 0 LASTPIN (-625 -150) $PN N5
J 2
(-635 -140);
DISPLAY 0.680851 (-635 -140);
PAINT MONO (-635 -140);
FORCEPROP 0 LASTPIN (-625 950) $PN N6
J 2
(-635 960);
DISPLAY 0.680851 (-635 960);
PAINT MONO (-635 960);
FORCEPROP 0 LASTPIN (-625 2050) $PN N7
J 2
(-635 2060);
DISPLAY 0.680851 (-635 2060);
PAINT MONO (-635 2060);
FORCEPROP 0 LASTPIN (-625 3150) $PN N8
J 2
(-635 3160);
DISPLAY 0.680851 (-635 3160);
PAINT MONO (-635 3160);
FORCEPROP 0 LASTPIN (-625 -200) $PN O5
J 2
(-635 -190);
DISPLAY 0.680851 (-635 -190);
PAINT MONO (-635 -190);
FORCEPROP 0 LASTPIN (-625 900) $PN O6
J 2
(-635 910);
DISPLAY 0.680851 (-635 910);
PAINT MONO (-635 910);
FORCEPROP 0 LASTPIN (-625 2000) $PN O7
J 2
(-635 2010);
DISPLAY 0.680851 (-635 2010);
PAINT MONO (-635 2010);
FORCEPROP 0 LASTPIN (-625 3100) $PN O8
J 2
(-635 3110);
DISPLAY 0.680851 (-635 3110);
PAINT MONO (-635 3110);
FORCEPROP 0 LASTPIN (-625 -250) $PN P5
J 2
(-635 -240);
DISPLAY 0.680851 (-635 -240);
PAINT MONO (-635 -240);
FORCEPROP 0 LASTPIN (-625 850) $PN P6
J 2
(-635 860);
DISPLAY 0.680851 (-635 860);
PAINT MONO (-635 860);
FORCEPROP 0 LASTPIN (-625 1950) $PN P7
J 2
(-635 1960);
DISPLAY 0.680851 (-635 1960);
PAINT MONO (-635 1960);
FORCEPROP 0 LASTPIN (-625 3050) $PN P8
J 2
(-635 3060);
DISPLAY 0.680851 (-635 3060);
PAINT MONO (-635 3060);
FORCEPROP 0 LASTPIN (-625 -300) $PN Q5
J 2
(-635 -290);
DISPLAY 0.680851 (-635 -290);
PAINT MONO (-635 -290);
FORCEPROP 0 LASTPIN (-625 800) $PN Q6
J 2
(-635 810);
DISPLAY 0.680851 (-635 810);
PAINT MONO (-635 810);
FORCEPROP 0 LASTPIN (-625 1900) $PN Q7
J 2
(-635 1910);
DISPLAY 0.680851 (-635 1910);
PAINT MONO (-635 1910);
FORCEPROP 0 LASTPIN (-625 3000) $PN Q8
J 2
(-635 3010);
DISPLAY 0.680851 (-635 3010);
PAINT MONO (-635 3010);
FORCEPROP 0 LASTPIN (-625 -350) $PN R5
J 2
(-635 -340);
DISPLAY 0.680851 (-635 -340);
PAINT MONO (-635 -340);
FORCEPROP 0 LASTPIN (-625 750) $PN R6
J 2
(-635 760);
DISPLAY 0.680851 (-635 760);
PAINT MONO (-635 760);
FORCEPROP 0 LASTPIN (-625 1850) $PN R7
J 2
(-635 1860);
DISPLAY 0.680851 (-635 1860);
PAINT MONO (-635 1860);
FORCEPROP 0 LASTPIN (-625 2950) $PN R8
J 2
(-635 2960);
DISPLAY 0.680851 (-635 2960);
PAINT MONO (-635 2960);
FORCEPROP 0 LASTPIN (-625 -400) $PN S5
J 2
(-635 -390);
DISPLAY 0.680851 (-635 -390);
PAINT MONO (-635 -390);
FORCEPROP 0 LASTPIN (-625 700) $PN S6
J 2
(-635 710);
DISPLAY 0.680851 (-635 710);
PAINT MONO (-635 710);
FORCEPROP 0 LASTPIN (-625 1800) $PN S7
J 2
(-635 1810);
DISPLAY 0.680851 (-635 1810);
PAINT MONO (-635 1810);
FORCEPROP 0 LASTPIN (-625 2900) $PN S8
J 2
(-635 2910);
DISPLAY 0.680851 (-635 2910);
PAINT MONO (-635 2910);
FORCEPROP 0 LASTPIN (-625 -450) $PN T5
J 2
(-635 -440);
DISPLAY 0.680851 (-635 -440);
PAINT MONO (-635 -440);
FORCEPROP 0 LASTPIN (-625 650) $PN T6
J 2
(-635 660);
DISPLAY 0.680851 (-635 660);
PAINT MONO (-635 660);
FORCEPROP 0 LASTPIN (-625 1750) $PN T7
J 2
(-635 1760);
DISPLAY 0.680851 (-635 1760);
PAINT MONO (-635 1760);
FORCEPROP 0 LASTPIN (-625 2850) $PN T8
J 2
(-635 2860);
DISPLAY 0.680851 (-635 2860);
PAINT MONO (-635 2860);
FORCEPROP 2 LAST CDS_LIB pure_quanta
J 0
(600 1675);
DISPLAY INVISIBLE (600 1675);
FORCEPROP 1 LAST PATH I75
J 0
(600 1675);
DISPLAY 0.723404 (600 1675);
PAINT GREEN (600 1675);
DISPLAY INVISIBLE (600 1675);
FORCEPROP 1 LAST CDS_LMAN_SYM_OUTLINE -1075,2225,1075,-2225
J 0
(600 1675);
DISPLAY 0.468085 (600 1675);
PAINT GREEN (600 1675);
DISPLAY INVISIBLE (600 1675);
FORCEPROP 1 LAST NEEDS_NO_SIZE TRUE
J 0
(600 1675);
DISPLAY 0.723404 (600 1675);
PAINT GREEN (600 1675);
DISPLAY INVISIBLE (600 1675);
FORCEPROP 0 LAST VALUE CONN160_10131762-101LF
J 0
(-425 4275);
DISPLAY 1.021277 (-425 4275);
DISPLAY INVISIBLE (-425 4275);
FORCEPROP 0 LAST $SEC 1
J 0
(-450 4150);
DISPLAY 0.680851 (-450 4150);
PAINT MONO (-450 4150);
DISPLAY INVISIBLE (-450 4150);
FORCEPROP 0 LAST CDS_SEC 1
J 0
(-450 4150);
DISPLAY 1.021277 (-450 4150);
DISPLAY INVISIBLE (-450 4150);
FORCEADD CONN160_10131762101LF..2
(5150 1750);
FORCEPROP 1 LAST PART_NUMBER DFHSG0FR007
J 0
(4100 4050);
DISPLAY 0.723404 (4100 4050);
PAINT GREEN (4100 4050);
DISPLAY INVISIBLE (4100 4050);
FORCEPROP 1 LAST MATERIAL IO
J 0
(4100 4000);
DISPLAY 0.723404 (4100 4000);
PAINT GREEN (4100 4000);
FORCEPROP 2 LAST PART_TYPE THLF
J 0
(4100 4150);
DISPLAY 1.021277 (4100 4150);
FORCEPROP 1 LAST LOCATION J112
J 0
(4100 4100);
DISPLAY 0.723404 (4100 4100);
PAINT GREEN (4100 4100);
FORCEPROP 0 LASTPIN (3925 575) $PN A1
J 2
(3915 585);
DISPLAY 0.680851 (3915 585);
PAINT MONO (3915 585);
FORCEPROP 0 LASTPIN (3925 1675) $PN A2
J 2
(3915 1685);
DISPLAY 0.680851 (3915 1685);
PAINT MONO (3915 1685);
FORCEPROP 0 LASTPIN (3925 2775) $PN A3
J 2
(3915 2785);
DISPLAY 0.680851 (3915 2785);
PAINT MONO (3915 2785);
FORCEPROP 0 LASTPIN (3925 3875) $PN A4
J 2
(3915 3885);
DISPLAY 0.680851 (3915 3885);
PAINT MONO (3915 3885);
FORCEPROP 0 LASTPIN (3925 525) $PN B1
J 2
(3915 535);
DISPLAY 0.680851 (3915 535);
PAINT MONO (3915 535);
FORCEPROP 0 LASTPIN (3925 1625) $PN B2
J 2
(3915 1635);
DISPLAY 0.680851 (3915 1635);
PAINT MONO (3915 1635);
FORCEPROP 0 LASTPIN (3925 2725) $PN B3
J 2
(3915 2735);
DISPLAY 0.680851 (3915 2735);
PAINT MONO (3915 2735);
FORCEPROP 0 LASTPIN (3925 3825) $PN B4
J 2
(3915 3835);
DISPLAY 0.680851 (3915 3835);
PAINT MONO (3915 3835);
FORCEPROP 0 LASTPIN (3925 475) $PN C1
J 2
(3915 485);
DISPLAY 0.680851 (3915 485);
PAINT MONO (3915 485);
FORCEPROP 0 LASTPIN (3925 1575) $PN C2
J 2
(3915 1585);
DISPLAY 0.680851 (3915 1585);
PAINT MONO (3915 1585);
FORCEPROP 0 LASTPIN (3925 2675) $PN C3
J 2
(3915 2685);
DISPLAY 0.680851 (3915 2685);
PAINT MONO (3915 2685);
FORCEPROP 0 LASTPIN (3925 3775) $PN C4
J 2
(3915 3785);
DISPLAY 0.680851 (3915 3785);
PAINT MONO (3915 3785);
FORCEPROP 0 LASTPIN (3925 425) $PN D1
J 2
(3915 435);
DISPLAY 0.680851 (3915 435);
PAINT MONO (3915 435);
FORCEPROP 0 LASTPIN (3925 1525) $PN D2
J 2
(3915 1535);
DISPLAY 0.680851 (3915 1535);
PAINT MONO (3915 1535);
FORCEPROP 0 LASTPIN (3925 2625) $PN D3
J 2
(3915 2635);
DISPLAY 0.680851 (3915 2635);
PAINT MONO (3915 2635);
FORCEPROP 0 LASTPIN (3925 3725) $PN D4
J 2
(3915 3735);
DISPLAY 0.680851 (3915 3735);
PAINT MONO (3915 3735);
FORCEPROP 0 LASTPIN (3925 375) $PN E1
J 2
(3915 385);
DISPLAY 0.680851 (3915 385);
PAINT MONO (3915 385);
FORCEPROP 0 LASTPIN (3925 1475) $PN E2
J 2
(3915 1485);
DISPLAY 0.680851 (3915 1485);
PAINT MONO (3915 1485);
FORCEPROP 0 LASTPIN (3925 2575) $PN E3
J 2
(3915 2585);
DISPLAY 0.680851 (3915 2585);
PAINT MONO (3915 2585);
FORCEPROP 0 LASTPIN (3925 3675) $PN E4
J 2
(3915 3685);
DISPLAY 0.680851 (3915 3685);
PAINT MONO (3915 3685);
FORCEPROP 0 LASTPIN (3925 325) $PN F1
J 2
(3915 335);
DISPLAY 0.680851 (3915 335);
PAINT MONO (3915 335);
FORCEPROP 0 LASTPIN (3925 1425) $PN F2
J 2
(3915 1435);
DISPLAY 0.680851 (3915 1435);
PAINT MONO (3915 1435);
FORCEPROP 0 LASTPIN (3925 2525) $PN F3
J 2
(3915 2535);
DISPLAY 0.680851 (3915 2535);
PAINT MONO (3915 2535);
FORCEPROP 0 LASTPIN (3925 3625) $PN F4
J 2
(3915 3635);
DISPLAY 0.680851 (3915 3635);
PAINT MONO (3915 3635);
FORCEPROP 0 LASTPIN (3925 275) $PN G1
J 2
(3915 285);
DISPLAY 0.680851 (3915 285);
PAINT MONO (3915 285);
FORCEPROP 0 LASTPIN (3925 1375) $PN G2
J 2
(3915 1385);
DISPLAY 0.680851 (3915 1385);
PAINT MONO (3915 1385);
FORCEPROP 0 LASTPIN (3925 2475) $PN G3
J 2
(3915 2485);
DISPLAY 0.680851 (3915 2485);
PAINT MONO (3915 2485);
FORCEPROP 0 LASTPIN (3925 3575) $PN G4
J 2
(3915 3585);
DISPLAY 0.680851 (3915 3585);
PAINT MONO (3915 3585);
FORCEPROP 0 LASTPIN (3925 225) $PN H1
J 2
(3915 235);
DISPLAY 0.680851 (3915 235);
PAINT MONO (3915 235);
FORCEPROP 0 LASTPIN (3925 1325) $PN H2
J 2
(3915 1335);
DISPLAY 0.680851 (3915 1335);
PAINT MONO (3915 1335);
FORCEPROP 0 LASTPIN (3925 2425) $PN H3
J 2
(3915 2435);
DISPLAY 0.680851 (3915 2435);
PAINT MONO (3915 2435);
FORCEPROP 0 LASTPIN (3925 3525) $PN H4
J 2
(3915 3535);
DISPLAY 0.680851 (3915 3535);
PAINT MONO (3915 3535);
FORCEPROP 0 LASTPIN (3925 175) $PN I1
J 2
(3915 185);
DISPLAY 0.680851 (3915 185);
PAINT MONO (3915 185);
FORCEPROP 0 LASTPIN (3925 1275) $PN I2
J 2
(3915 1285);
DISPLAY 0.680851 (3915 1285);
PAINT MONO (3915 1285);
FORCEPROP 0 LASTPIN (3925 2375) $PN I3
J 2
(3915 2385);
DISPLAY 0.680851 (3915 2385);
PAINT MONO (3915 2385);
FORCEPROP 0 LASTPIN (3925 3475) $PN I4
J 2
(3915 3485);
DISPLAY 0.680851 (3915 3485);
PAINT MONO (3915 3485);
FORCEPROP 0 LASTPIN (3925 125) $PN J1
J 2
(3915 135);
DISPLAY 0.680851 (3915 135);
PAINT MONO (3915 135);
FORCEPROP 0 LASTPIN (3925 1225) $PN J2
J 2
(3915 1235);
DISPLAY 0.680851 (3915 1235);
PAINT MONO (3915 1235);
FORCEPROP 0 LASTPIN (3925 2325) $PN J3
J 2
(3915 2335);
DISPLAY 0.680851 (3915 2335);
PAINT MONO (3915 2335);
FORCEPROP 0 LASTPIN (3925 3425) $PN J4
J 2
(3915 3435);
DISPLAY 0.680851 (3915 3435);
PAINT MONO (3915 3435);
FORCEPROP 0 LASTPIN (3925 75) $PN K1
J 2
(3915 85);
DISPLAY 0.680851 (3915 85);
PAINT MONO (3915 85);
FORCEPROP 0 LASTPIN (3925 1175) $PN K2
J 2
(3915 1185);
DISPLAY 0.680851 (3915 1185);
PAINT MONO (3915 1185);
FORCEPROP 0 LASTPIN (3925 2275) $PN K3
J 2
(3915 2285);
DISPLAY 0.680851 (3915 2285);
PAINT MONO (3915 2285);
FORCEPROP 0 LASTPIN (3925 3375) $PN K4
J 2
(3915 3385);
DISPLAY 0.680851 (3915 3385);
PAINT MONO (3915 3385);
FORCEPROP 0 LASTPIN (3925 25) $PN L1
J 2
(3915 35);
DISPLAY 0.680851 (3915 35);
PAINT MONO (3915 35);
FORCEPROP 0 LASTPIN (3925 1125) $PN L2
J 2
(3915 1135);
DISPLAY 0.680851 (3915 1135);
PAINT MONO (3915 1135);
FORCEPROP 0 LASTPIN (3925 2225) $PN L3
J 2
(3915 2235);
DISPLAY 0.680851 (3915 2235);
PAINT MONO (3915 2235);
FORCEPROP 0 LASTPIN (3925 3325) $PN L4
J 2
(3915 3335);
DISPLAY 0.680851 (3915 3335);
PAINT MONO (3915 3335);
FORCEPROP 0 LASTPIN (3925 -25) $PN M1
J 2
(3915 -15);
DISPLAY 0.680851 (3915 -15);
PAINT MONO (3915 -15);
FORCEPROP 0 LASTPIN (3925 1075) $PN M2
J 2
(3915 1085);
DISPLAY 0.680851 (3915 1085);
PAINT MONO (3915 1085);
FORCEPROP 0 LASTPIN (3925 2175) $PN M3
J 2
(3915 2185);
DISPLAY 0.680851 (3915 2185);
PAINT MONO (3915 2185);
FORCEPROP 0 LASTPIN (3925 3275) $PN M4
J 2
(3915 3285);
DISPLAY 0.680851 (3915 3285);
PAINT MONO (3915 3285);
FORCEPROP 0 LASTPIN (3925 -75) $PN N1
J 2
(3915 -65);
DISPLAY 0.680851 (3915 -65);
PAINT MONO (3915 -65);
FORCEPROP 0 LASTPIN (3925 1025) $PN N2
J 2
(3915 1035);
DISPLAY 0.680851 (3915 1035);
PAINT MONO (3915 1035);
FORCEPROP 0 LASTPIN (3925 2125) $PN N3
J 2
(3915 2135);
DISPLAY 0.680851 (3915 2135);
PAINT MONO (3915 2135);
FORCEPROP 0 LASTPIN (3925 3225) $PN N4
J 2
(3915 3235);
DISPLAY 0.680851 (3915 3235);
PAINT MONO (3915 3235);
FORCEPROP 0 LASTPIN (3925 -125) $PN O1
J 2
(3915 -115);
DISPLAY 0.680851 (3915 -115);
PAINT MONO (3915 -115);
FORCEPROP 0 LASTPIN (3925 975) $PN O2
J 2
(3915 985);
DISPLAY 0.680851 (3915 985);
PAINT MONO (3915 985);
FORCEPROP 0 LASTPIN (3925 2075) $PN O3
J 2
(3915 2085);
DISPLAY 0.680851 (3915 2085);
PAINT MONO (3915 2085);
FORCEPROP 0 LASTPIN (3925 3175) $PN O4
J 2
(3915 3185);
DISPLAY 0.680851 (3915 3185);
PAINT MONO (3915 3185);
FORCEPROP 0 LASTPIN (3925 -175) $PN P1
J 2
(3915 -165);
DISPLAY 0.680851 (3915 -165);
PAINT MONO (3915 -165);
FORCEPROP 0 LASTPIN (3925 925) $PN P2
J 2
(3915 935);
DISPLAY 0.680851 (3915 935);
PAINT MONO (3915 935);
FORCEPROP 0 LASTPIN (3925 2025) $PN P3
J 2
(3915 2035);
DISPLAY 0.680851 (3915 2035);
PAINT MONO (3915 2035);
FORCEPROP 0 LASTPIN (3925 3125) $PN P4
J 2
(3915 3135);
DISPLAY 0.680851 (3915 3135);
PAINT MONO (3915 3135);
FORCEPROP 0 LASTPIN (3925 -225) $PN Q1
J 2
(3915 -215);
DISPLAY 0.680851 (3915 -215);
PAINT MONO (3915 -215);
FORCEPROP 0 LASTPIN (3925 875) $PN Q2
J 2
(3915 885);
DISPLAY 0.680851 (3915 885);
PAINT MONO (3915 885);
FORCEPROP 0 LASTPIN (3925 1975) $PN Q3
J 2
(3915 1985);
DISPLAY 0.680851 (3915 1985);
PAINT MONO (3915 1985);
FORCEPROP 0 LASTPIN (3925 3075) $PN Q4
J 2
(3915 3085);
DISPLAY 0.680851 (3915 3085);
PAINT MONO (3915 3085);
FORCEPROP 0 LASTPIN (3925 -275) $PN R1
J 2
(3915 -265);
DISPLAY 0.680851 (3915 -265);
PAINT MONO (3915 -265);
FORCEPROP 0 LASTPIN (3925 825) $PN R2
J 2
(3915 835);
DISPLAY 0.680851 (3915 835);
PAINT MONO (3915 835);
FORCEPROP 0 LASTPIN (3925 1925) $PN R3
J 2
(3915 1935);
DISPLAY 0.680851 (3915 1935);
PAINT MONO (3915 1935);
FORCEPROP 0 LASTPIN (3925 3025) $PN R4
J 2
(3915 3035);
DISPLAY 0.680851 (3915 3035);
PAINT MONO (3915 3035);
FORCEPROP 0 LASTPIN (3925 -325) $PN S1
J 2
(3915 -315);
DISPLAY 0.680851 (3915 -315);
PAINT MONO (3915 -315);
FORCEPROP 0 LASTPIN (3925 775) $PN S2
J 2
(3915 785);
DISPLAY 0.680851 (3915 785);
PAINT MONO (3915 785);
FORCEPROP 0 LASTPIN (3925 1875) $PN S3
J 2
(3915 1885);
DISPLAY 0.680851 (3915 1885);
PAINT MONO (3915 1885);
FORCEPROP 0 LASTPIN (3925 2975) $PN S4
J 2
(3915 2985);
DISPLAY 0.680851 (3915 2985);
PAINT MONO (3915 2985);
FORCEPROP 0 LASTPIN (3925 -375) $PN T1
J 2
(3915 -365);
DISPLAY 0.680851 (3915 -365);
PAINT MONO (3915 -365);
FORCEPROP 0 LASTPIN (3925 725) $PN T2
J 2
(3915 735);
DISPLAY 0.680851 (3915 735);
PAINT MONO (3915 735);
FORCEPROP 0 LASTPIN (3925 1825) $PN T3
J 2
(3915 1835);
DISPLAY 0.680851 (3915 1835);
PAINT MONO (3915 1835);
FORCEPROP 0 LASTPIN (3925 2925) $PN T4
J 2
(3915 2935);
DISPLAY 0.680851 (3915 2935);
PAINT MONO (3915 2935);
FORCEPROP 2 LAST CDS_LIB pure_quanta
J 0
(5150 1750);
DISPLAY INVISIBLE (5150 1750);
FORCEPROP 1 LAST PATH I76
J 0
(5150 1750);
DISPLAY 0.723404 (5150 1750);
PAINT GREEN (5150 1750);
DISPLAY INVISIBLE (5150 1750);
FORCEPROP 1 LAST CDS_LMAN_SYM_OUTLINE -1075,2225,1075,-2225
J 0
(5150 1750);
DISPLAY 0.468085 (5150 1750);
PAINT GREEN (5150 1750);
DISPLAY INVISIBLE (5150 1750);
FORCEPROP 1 LAST NEEDS_NO_SIZE TRUE
J 0
(5150 1750);
DISPLAY 0.723404 (5150 1750);
PAINT GREEN (5150 1750);
DISPLAY INVISIBLE (5150 1750);
FORCEPROP 0 LAST VALUE CONN160_10131762-101LF
J 0
(4100 4325);
DISPLAY 1.021277 (4100 4325);
DISPLAY INVISIBLE (4100 4325);
FORCEPROP 0 LAST $SEC 2
J 0
(4100 4200);
DISPLAY 0.680851 (4100 4200);
PAINT MONO (4100 4200);
DISPLAY INVISIBLE (4100 4200);
FORCEPROP 0 LAST CDS_SEC 2
J 0
(4100 4200);
DISPLAY 1.021277 (4100 4200);
DISPLAY INVISIBLE (4100 4200);
FORCEADD UNIVERSAL_GND..1
(-775 -925);
FORCEPROP 3 LASTPIN (-775 -875) SIG_NAME GND\g
J 0
(-765 -865);
DISPLAY 0.659574 (-765 -865);
PAINT MONO (-765 -865);
DISPLAY INVISIBLE (-765 -865);
FORCEPROP 1 LAST HDL_POWER GND
J 1
(-750 -1000);
DISPLAY 0.872340 (-750 -1000);
PAINT GREEN (-750 -1000);
DISPLAY INVISIBLE (-750 -1000);
FORCEPROP 1 LAST PATH I77
J 0
(-700 -925);
DISPLAY 0.872340 (-700 -925);
PAINT AQUA (-700 -925);
DISPLAY INVISIBLE (-700 -925);
FORCEPROP 2 LAST CDS_LIB logical_power
J 0
(-775 -925);
DISPLAY INVISIBLE (-775 -925);
FORCEADD UNIVERSAL_GND..1
(3775 -800);
FORCEPROP 3 LASTPIN (3775 -750) SIG_NAME GND\g
J 0
(3785 -740);
DISPLAY 0.659574 (3785 -740);
PAINT MONO (3785 -740);
DISPLAY INVISIBLE (3785 -740);
FORCEPROP 1 LAST HDL_POWER GND
J 1
(3800 -875);
DISPLAY 0.872340 (3800 -875);
PAINT GREEN (3800 -875);
DISPLAY INVISIBLE (3800 -875);
FORCEPROP 1 LAST PATH I78
J 0
(3850 -800);
DISPLAY 0.872340 (3850 -800);
PAINT AQUA (3850 -800);
DISPLAY INVISIBLE (3850 -800);
FORCEPROP 2 LAST CDS_LIB logical_power
J 0
(3775 -800);
DISPLAY INVISIBLE (3775 -800);
FORCEADD QUANTA_TITLE_BLOCK_C..1
(6350 -1625);
FORCEPROP 0 LAST CDS_CON_LAST_MODIFIED Fri Aug 25 14:02:04 2023
J 0
(4465 -1610);
PAINT MONO (4465 -1610);
DISPLAY INVISIBLE (4465 -1610);
FORCEPROP 2 LAST CUSTOM_TXT_CDS <XR_PAGE_TITLE>
J 0
(-1540 3625);
DISPLAY 0.638298 (-1540 3625);
PAINT PINK (-1540 3625);
DISPLAY INVISIBLE (-1540 3625);
FORCEPROP 2 LAST CUSTOM_TXT_CDS <Q_NUMBER>
J 0
(4947 -1522);
DISPLAY 1.212766 (4947 -1522);
FORCEPROP 2 LAST CUSTOM_TXT_CDS <Q_PROJ>
J 0
(3968 -1523);
DISPLAY 1.212766 (3968 -1523);
FORCEPROP 2 LAST CUSTOM_TXT_CDS <CON_LAST_MODIFIED>
J 0
(4465 -1610);
DISPLAY 0.978723 (4465 -1610);
FORCEPROP 2 LAST CUSTOM_TXT_CDS <NAME_1>
J 0
(3175 -1450);
FORCEPROP 2 LAST CUSTOM_TXT_CDS <NAME_2>
J 0
(3175 -1575);
FORCEPROP 2 LAST CUSTOM_TXT_CDS <Q_REV>
J 0
(6166 -1522);
DISPLAY 1.212766 (6166 -1522);
FORCEPROP 1 LAST CUSTOM_TXT_CDS <CON_PAGE_NUM> OF <CON_TOTAL_PAGES>
J 0
(5904 -1607);
DISPLAY 0.978723 (5904 -1607);
FORCEPROP 1 LAST Q_TITLE PCIE - CPU1_EXAMAX_P0/P4_X16
J 0
(-3016 -1599);
DISPLAY 1.957447 (-3016 -1599);
PAINT GREEN (-3016 -1599);
FORCEPROP 1 LAST Q_DEPT 
J 1
(2587 -1576);
DISPLAY 1.957447 (2587 -1576);
PAINT GREEN (2587 -1576);
FORCEPROP 2 LAST CDS_XR_PAGE_TITLE CR-143 : @S9S_MB_2U_LIB.S9S_MB_2U(SCH_1):PAGE143
J 0
(-1540 3625);
DISPLAY 0.638298 (-1540 3625);
PAINT PINK (-1540 3625);
DISPLAY INVISIBLE (-1540 3625);
FORCEPROP 2 LAST PAGE_BORDER TRUE
J 0
(-1540 3625);
DISPLAY 0.638298 (-1540 3625);
PAINT PINK (-1540 3625);
DISPLAY INVISIBLE (-1540 3625);
FORCEPROP 1 LAST CDS_LMAN_SYM_OUTLINE -9475,6775,100,-125
J 0
(6350 -1625);
DISPLAY 0.468085 (6350 -1625);
PAINT GREEN (6350 -1625);
DISPLAY INVISIBLE (6350 -1625);
FORCEPROP 2 LAST CDS_LIB pure_quanta
J 0
(6350 -1625);
PAINT MONO (6350 -1625);
DISPLAY INVISIBLE (6350 -1625);
FORCEPROP 1 LAST COMMENT_BODY TRUE
J 0
(6362 -1638);
DISPLAY 0.978723 (6362 -1638);
PAINT GREEN (6362 -1638);
DISPLAY INVISIBLE (6362 -1638);
WIRE 16 -1 (-775 -875)(-775 -450);
WIRE 16 -1 (3775 -750)(3775 -375);
WIRE 16 -1 (-625 2000)(-1950 2000);
FORCEPROP 2 LAST SIG_NAME P3E_PCH_NVS_RX_DN<1>
J 0
(-1660 2010);
DISPLAY 0.638298 (-1660 2010);
WIRE 16 -1 (-625 1950)(-1950 1950);
FORCEPROP 2 LAST SIG_NAME P3E_PCH_NVS_RX_DP<1>
J 0
(-1660 1960);
DISPLAY 0.638298 (-1660 1960);
WIRE 16 -1 (-625 3100)(-1950 3100);
FORCEPROP 2 LAST SIG_NAME P3E_PCH_NVS_RX_DP<0>
J 0
(-1660 3110);
DISPLAY 0.638298 (-1660 3110);
WIRE 16 -1 (-625 2850)(-1950 2850);
FORCEPROP 2 LAST SIG_NAME RST_PERST_0_SWB_BUF_N
J 0
(-1660 2860);
DISPLAY 0.638298 (-1660 2860);
WIRE 16 -1 (-625 3000)(-1950 3000);
FORCEPROP 2 LAST SIG_NAME P3E_PCH_NVS_TX_C_DN<0>
J 0
(-1660 3010);
DISPLAY 0.638298 (-1660 3010);
WIRE 16 -1 (-625 2950)(-1950 2950);
FORCEPROP 2 LAST SIG_NAME P3E_PCH_NVS_TX_C_DP<0>
J 0
(-1660 2960);
DISPLAY 0.638298 (-1660 2960);
WIRE 16 -1 (-625 2700)(-1950 2700);
FORCEPROP 2 LAST SIG_NAME PRSNT_SWB_N
J 0
(-1660 2710);
DISPLAY 0.638298 (-1660 2710);
WIRE 16 -1 (-625 2550)(-1950 2550);
FORCEPROP 2 LAST SIG_NAME P5E_CPU1_PE0_RX_DP<9>
J 0
(-1660 2560);
DISPLAY 0.638298 (-1660 2560);
WIRE 16 -1 (-625 2450)(-1950 2450);
FORCEPROP 2 LAST SIG_NAME P5E_CPU1_PE4_RX_DN<6>
J 0
(-1660 2460);
DISPLAY 0.638298 (-1660 2460);
WIRE 16 -1 (-625 2600)(-1950 2600);
FORCEPROP 2 LAST SIG_NAME P5E_CPU1_PE0_RX_DN<9>
J 0
(-1660 2610);
DISPLAY 0.638298 (-1660 2610);
WIRE 16 -1 (-625 1850)(-1950 1850);
FORCEPROP 2 LAST SIG_NAME P3E_PCH_NVS_TX_C_DN<1>
J 0
(-1660 1860);
DISPLAY 0.638298 (-1660 1860);
WIRE 16 -1 (-625 1800)(-1950 1800);
FORCEPROP 2 LAST SIG_NAME P3E_PCH_NVS_TX_C_DP<1>
J 0
(-1660 1810);
DISPLAY 0.638298 (-1660 1810);
WIRE 16 -1 (-625 1550)(-1925 1550);
FORCEPROP 2 LAST SIG_NAME P5E_CPU1_PE0_RX_DN<10>
J 0
(-1660 1560);
DISPLAY 0.638298 (-1660 1560);
WIRE 16 -1 (-625 1500)(-1925 1500);
FORCEPROP 2 LAST SIG_NAME P5E_CPU1_PE0_RX_DP<10>
J 0
(-1660 1510);
DISPLAY 0.638298 (-1660 1510);
WIRE 16 -1 (-625 1400)(-1925 1400);
FORCEPROP 2 LAST SIG_NAME P5E_CPU1_PE4_RX_DP<5>
J 0
(-1660 1410);
DISPLAY 0.638298 (-1660 1410);
WIRE 16 -1 (-625 1350)(-1925 1350);
FORCEPROP 2 LAST SIG_NAME P5E_CPU1_PE4_RX_DN<5>
J 0
(-1660 1360);
DISPLAY 0.638298 (-1660 1360);
WIRE 16 -1 (-625 1050)(-1925 1050);
FORCEPROP 2 LAST SIG_NAME P5E_CPU1_PE4_TX_C_DP<5>
J 0
(-1660 1060);
DISPLAY 0.638298 (-1660 1060);
WIRE 16 -1 (-625 950)(-1925 950);
FORCEPROP 2 LAST SIG_NAME P2E_MB_BMC_RX_DN<0>
J 0
(-1660 960);
DISPLAY 0.638298 (-1660 960);
WIRE 16 -1 (-625 900)(-1925 900);
FORCEPROP 2 LAST SIG_NAME P2E_MB_BMC_RX_DP<0>
J 0
(-1660 910);
DISPLAY 0.638298 (-1660 910);
WIRE 16 -1 (-625 800)(-1925 800);
FORCEPROP 2 LAST SIG_NAME P2E_MB_BMC_TX_BUF_C_DN<0>
J 0
(-1660 810);
DISPLAY 0.638298 (-1660 810);
WIRE 16 -1 (-625 750)(-1925 750);
FORCEPROP 2 LAST SIG_NAME P2E_MB_BMC_TX_BUF_C_DP<0>
J 0
(-1660 760);
DISPLAY 0.638298 (-1660 760);
WIRE 16 -1 (-625 650)(-1925 650);
FORCEPROP 2 LAST SIG_NAME GPU_FPGA_THERM_OVERT_N
J 0
(-1660 660);
DISPLAY 0.638298 (-1660 660);
WIRE 16 -1 (-625 500)(-1925 500);
FORCEPROP 2 LAST SIG_NAME RST_PERST_1_SWB_BUF_N
J 0
(-1660 510);
DISPLAY 0.638298 (-1660 510);
WIRE 16 -1 (-625 350)(-1925 350);
FORCEPROP 2 LAST SIG_NAME P5E_CPU1_PE0_RX_DN<11>
J 0
(-1660 360);
DISPLAY 0.638298 (-1660 360);
WIRE 16 -1 (-1925 250)(-625 250);
FORCEPROP 2 LAST SIG_NAME P5E_CPU1_PE4_RX_DN<4>
J 0
(-1660 260);
DISPLAY 0.638298 (-1660 260);
WIRE 16 -1 (-1925 200)(-625 200);
FORCEPROP 2 LAST SIG_NAME P5E_CPU1_PE4_RX_DP<4>
J 0
(-1660 210);
DISPLAY 0.638298 (-1660 210);
WIRE 16 -1 (-625 100)(-1925 100);
FORCEPROP 2 LAST SIG_NAME P5E_CPU1_PE0_TX_C_DN<11>
J 0
(-1660 110);
DISPLAY 0.638298 (-1660 110);
WIRE 16 -1 (-625 2300)(-1950 2300);
FORCEPROP 2 LAST SIG_NAME P5E_CPU1_PE0_TX_C_DN<9>
J 0
(-1660 2310);
DISPLAY 0.638298 (-1660 2310);
WIRE 16 -1 (-625 3250)(-1950 3250);
FORCEPROP 2 LAST SIG_NAME P5E_CPU1_PE4_TX_C_DP<7>
J 0
(-1660 3260);
DISPLAY 0.638298 (-1660 3260);
WIRE 16 -1 (-625 3300)(-1950 3300);
FORCEPROP 2 LAST SIG_NAME P5E_CPU1_PE4_TX_C_DN<7>
J 0
(-1660 3310);
DISPLAY 0.638298 (-1660 3310);
WIRE 16 -1 (-625 3450)(-1950 3450);
FORCEPROP 2 LAST SIG_NAME P5E_CPU1_PE0_TX_C_DN<8>
J 0
(-1660 3460);
DISPLAY 0.638298 (-1660 3460);
WIRE 16 -1 (-625 3550)(-1950 3550);
FORCEPROP 2 LAST SIG_NAME P5E_CPU1_PE4_RX_DN<7>
J 0
(-1660 3560);
DISPLAY 0.638298 (-1660 3560);
WIRE 16 -1 (-625 3700)(-1950 3700);
FORCEPROP 2 LAST SIG_NAME P5E_CPU1_PE0_RX_DP<8>
J 0
(-1660 3710);
DISPLAY 0.638298 (-1660 3710);
WIRE 16 -1 (-625 3750)(-1950 3750);
FORCEPROP 2 LAST SIG_NAME P5E_CPU1_PE0_RX_DN<8>
J 0
(-1660 3760);
DISPLAY 0.638298 (-1660 3760);
WIRE 16 -1 (-625 3600)(-1950 3600);
FORCEPROP 2 LAST SIG_NAME P5E_CPU1_PE4_RX_DP<7>
J 0
(-1660 3610);
DISPLAY 0.638298 (-1660 3610);
WIRE 16 -1 (-625 3400)(-1950 3400);
FORCEPROP 2 LAST SIG_NAME P5E_CPU1_PE0_TX_C_DP<8>
J 0
(-1660 3410);
DISPLAY 0.638298 (-1660 3410);
WIRE 16 -1 (-625 3150)(-1950 3150);
FORCEPROP 2 LAST SIG_NAME P3E_PCH_NVS_RX_DN<0>
J 0
(-1660 3160);
DISPLAY 0.638298 (-1660 3160);
WIRE 16 -1 (3925 2775)(2700 2775);
FORCEPROP 2 LAST SIG_NAME HGX_DETECT_N_ISO
J 0
(2865 2785);
DISPLAY 0.638298 (2865 2785);
WIRE 16 -1 (3925 2675)(2700 2675);
FORCEPROP 2 LAST SIG_NAME P5E_CPU1_PE0_RX_DN<13>
J 0
(2865 2685);
DISPLAY 0.638298 (2865 2685);
WIRE 16 -1 (3925 3025)(2700 3025);
FORCEPROP 2 LAST SIG_NAME SMB_1_BMC_GPU_BUF_SDA
J 0
(2865 3035);
DISPLAY 0.638298 (2865 3035);
WIRE 16 -1 (3925 3075)(2700 3075);
FORCEPROP 2 LAST SIG_NAME SMB_1_BMC_GPU_BUF_SCL
J 0
(2865 3085);
DISPLAY 0.638298 (2865 3085);
WIRE 16 -1 (3925 2925)(2700 2925);
FORCEPROP 2 LAST SIG_NAME GPU_NVS_PWR_BRAKE_N_BUF
J 0
(2865 2935);
DISPLAY 0.638298 (2865 2935);
WIRE 16 -1 (3925 -375)(3775 -375);
WIRE 16 -1 (3775 -375)(3775 -225);
WIRE 16 -1 (3925 -225)(3775 -225);
WIRE 16 -1 (3775 -225)(3775 -75);
WIRE 16 -1 (3925 -75)(3775 -75);
WIRE 16 -1 (3775 -75)(3775 75);
WIRE 16 -1 (3925 75)(3775 75);
WIRE 16 -1 (3775 75)(3775 225);
WIRE 16 -1 (3925 225)(3775 225);
WIRE 16 -1 (3775 225)(3775 375);
WIRE 16 -1 (3925 375)(3775 375);
WIRE 16 -1 (3775 375)(3775 525);
WIRE 16 -1 (3925 525)(3775 525);
WIRE 16 -1 (3775 525)(3775 775);
WIRE 16 -1 (3925 775)(3775 775);
WIRE 16 -1 (3775 775)(3775 925);
WIRE 16 -1 (3925 925)(3775 925);
WIRE 16 -1 (3775 925)(3775 1075);
WIRE 16 -1 (3925 1075)(3775 1075);
WIRE 16 -1 (3775 1075)(3775 1225);
WIRE 16 -1 (3925 1225)(3775 1225);
WIRE 16 -1 (3775 1225)(3775 1375);
WIRE 16 -1 (3925 1375)(3775 1375);
WIRE 16 -1 (3775 1375)(3775 1525);
WIRE 16 -1 (3925 1525)(3775 1525);
WIRE 16 -1 (3775 1525)(3775 1675);
WIRE 16 -1 (3925 1675)(3775 1675);
WIRE 16 -1 (3775 1675)(3775 1825);
WIRE 16 -1 (3925 1825)(3775 1825);
WIRE 16 -1 (3775 1825)(3775 1975);
WIRE 16 -1 (3925 1975)(3775 1975);
WIRE 16 -1 (3775 1975)(3775 2125);
WIRE 16 -1 (3925 2125)(3775 2125);
WIRE 16 -1 (3775 2275)(3775 2125);
WIRE 16 -1 (3925 2275)(3775 2275);
WIRE 16 -1 (3775 2425)(3775 2275);
WIRE 16 -1 (3925 2425)(3775 2425);
WIRE 16 -1 (3775 2575)(3775 2425);
WIRE 16 -1 (3925 2575)(3775 2575);
WIRE 16 -1 (3775 2725)(3775 2575);
WIRE 16 -1 (3925 2725)(3775 2725);
WIRE 16 -1 (3775 2975)(3775 2725);
WIRE 16 -1 (3925 2975)(3775 2975);
WIRE 16 -1 (3775 3125)(3775 2975);
WIRE 16 -1 (3925 3125)(3775 3125);
WIRE 16 -1 (3775 3275)(3775 3125);
WIRE 16 -1 (3925 3275)(3775 3275);
WIRE 16 -1 (3775 3425)(3775 3275);
WIRE 16 -1 (3925 3425)(3775 3425);
WIRE 16 -1 (3775 3575)(3775 3425);
WIRE 16 -1 (3925 3575)(3775 3575);
WIRE 16 -1 (3775 3725)(3775 3575);
WIRE 16 -1 (3925 3725)(3775 3725);
WIRE 16 -1 (3775 3875)(3775 3725);
WIRE 16 -1 (3925 3875)(3775 3875);
WIRE 16 -1 (3925 3325)(2700 3325);
FORCEPROP 2 LAST SIG_NAME P5E_CPU1_PE4_TX_C_DP<3>
J 0
(2865 3335);
DISPLAY 0.638298 (2865 3335);
WIRE 16 -1 (3925 3175)(2700 3175);
FORCEPROP 2 LAST SIG_NAME CLK_100M_GPU_1_DP
J 0
(2865 3185);
DISPLAY 0.638298 (2865 3185);
WIRE 16 -1 (3925 3225)(2700 3225);
FORCEPROP 2 LAST SIG_NAME CLK_100M_GPU_1_DN
J 0
(2865 3235);
DISPLAY 0.638298 (2865 3235);
WIRE 16 -1 (3925 2625)(2700 2625);
FORCEPROP 2 LAST SIG_NAME P5E_CPU1_PE0_RX_DP<13>
J 0
(2865 2635);
DISPLAY 0.638298 (2865 2635);
WIRE 16 -1 (3925 2525)(2700 2525);
FORCEPROP 2 LAST SIG_NAME P5E_CPU1_PE4_RX_DN<2>
J 0
(2865 2535);
DISPLAY 0.638298 (2865 2535);
WIRE 16 -1 (3925 2475)(2700 2475);
FORCEPROP 2 LAST SIG_NAME P5E_CPU1_PE4_RX_DP<2>
J 0
(2865 2485);
DISPLAY 0.638298 (2865 2485);
WIRE 16 -1 (3925 2325)(2700 2325);
FORCEPROP 2 LAST SIG_NAME P5E_CPU1_PE0_TX_C_DP<13>
J 0
(2865 2335);
DISPLAY 0.638298 (2865 2335);
WIRE 16 -1 (3925 2225)(2700 2225);
FORCEPROP 2 LAST SIG_NAME P5E_CPU1_PE4_TX_C_DN<2>
J 0
(2865 2235);
DISPLAY 0.638298 (2865 2235);
WIRE 16 -1 (2700 2175)(3925 2175);
FORCEPROP 2 LAST SIG_NAME P5E_CPU1_PE4_TX_C_DP<2>
J 0
(2865 2185);
DISPLAY 0.638298 (2865 2185);
WIRE 16 -1 (3925 2075)(2700 2075);
FORCEPROP 2 LAST SIG_NAME CLK_100M_SWB_DN
J 0
(2865 2085);
DISPLAY 0.638298 (2865 2085);
WIRE 16 -1 (3925 2025)(2700 2025);
FORCEPROP 2 LAST SIG_NAME CLK_100M_SWB_DP
J 0
(2865 2035);
DISPLAY 0.638298 (2865 2035);
WIRE 16 -1 (3925 1925)(2700 1925);
FORCEPROP 2 LAST SIG_NAME SMB_2_BMC_GPU_BUF_SCL
J 0
(2865 1935);
DISPLAY 0.638298 (2865 1935);
WIRE 16 -1 (3925 1875)(2700 1875);
FORCEPROP 2 LAST SIG_NAME SMB_2_BMC_GPU_BUF_SDA
J 0
(2865 1885);
DISPLAY 0.638298 (2865 1885);
WIRE 16 -1 (3925 1625)(2700 1625);
FORCEPROP 2 LAST SIG_NAME P5E_CPU1_PE0_RX_DN<14>
J 0
(2865 1635);
DISPLAY 0.638298 (2865 1635);
WIRE 16 -1 (3925 1575)(2700 1575);
FORCEPROP 2 LAST SIG_NAME P5E_CPU1_PE0_RX_DP<14>
J 0
(2865 1585);
DISPLAY 0.638298 (2865 1585);
WIRE 16 -1 (3925 1475)(2700 1475);
FORCEPROP 2 LAST SIG_NAME P5E_CPU1_PE4_RX_DP<1>
J 0
(2865 1485);
DISPLAY 0.638298 (2865 1485);
WIRE 16 -1 (3925 1275)(2700 1275);
FORCEPROP 2 LAST SIG_NAME P5E_CPU1_PE0_TX_C_DP<14>
J 0
(2865 1285);
DISPLAY 0.638298 (2865 1285);
WIRE 16 -1 (3925 1125)(2700 1125);
FORCEPROP 2 LAST SIG_NAME P5E_CPU1_PE4_TX_C_DN<1>
J 0
(2865 1135);
DISPLAY 0.638298 (2865 1135);
WIRE 16 -1 (3925 1025)(2675 1025);
FORCEPROP 2 LAST SIG_NAME NC_J112_N2
J 0
(2890 1035);
DISPLAY 0.638298 (2890 1035);
WIRE 16 -1 (3925 975)(2675 975);
FORCEPROP 2 LAST SIG_NAME NC_J112_O2
J 0
(2890 985);
DISPLAY 0.638298 (2890 985);
WIRE 16 -1 (3925 875)(2700 875);
FORCEPROP 2 LAST SIG_NAME CLK_100M_GPU_FPGA_DN
J 0
(2865 885);
DISPLAY 0.638298 (2865 885);
WIRE 16 -1 (3925 725)(2700 725);
FORCEPROP 2 LAST SIG_NAME GPU_FPGA_READY
J 0
(2865 735);
DISPLAY 0.638298 (2865 735);
WIRE 16 -1 (3925 575)(2700 575);
FORCEPROP 2 LAST SIG_NAME RST_PERST_2_SWB_BUF_N
J 0
(2865 585);
DISPLAY 0.638298 (2865 585);
WIRE 16 -1 (3925 425)(2700 425);
FORCEPROP 2 LAST SIG_NAME P5E_CPU1_PE0_RX_DP<15>
J 0
(2865 435);
DISPLAY 0.638298 (2865 435);
WIRE 16 -1 (3925 325)(2700 325);
FORCEPROP 2 LAST SIG_NAME P5E_CPU1_PE4_RX_DN<0>
J 0
(2865 335);
DISPLAY 0.638298 (2865 335);
WIRE 16 -1 (3925 -325)(2700 -325);
FORCEPROP 2 LAST SIG_NAME USB2_HUB_BUF_SWB_DP
J 0
(2865 -315);
DISPLAY 0.638298 (2865 -315);
WIRE 16 -1 (3925 -175)(2700 -175);
FORCEPROP 2 LAST SIG_NAME CLK_100M_GPU_2_DP
J 0
(2865 -165);
DISPLAY 0.638298 (2865 -165);
WIRE 16 -1 (3925 -125)(2700 -125);
FORCEPROP 2 LAST SIG_NAME CLK_100M_GPU_2_DN
J 0
(2865 -115);
DISPLAY 0.638298 (2865 -115);
WIRE 16 -1 (3925 -25)(2700 -25);
FORCEPROP 2 LAST SIG_NAME P5E_CPU1_PE4_TX_C_DP<0>
J 0
(2865 -15);
DISPLAY 0.638298 (2865 -15);
WIRE 16 -1 (3925 25)(2700 25);
FORCEPROP 2 LAST SIG_NAME P5E_CPU1_PE4_TX_C_DN<0>
J 0
(2865 35);
DISPLAY 0.638298 (2865 35);
WIRE 16 -1 (3925 125)(2700 125);
FORCEPROP 2 LAST SIG_NAME P5E_CPU1_PE0_TX_C_DP<15>
J 0
(2865 135);
DISPLAY 0.638298 (2865 135);
WIRE 16 -1 (3925 175)(2700 175);
FORCEPROP 2 LAST SIG_NAME P5E_CPU1_PE0_TX_C_DN<15>
J 0
(2865 185);
DISPLAY 0.638298 (2865 185);
WIRE 16 -1 (3925 275)(2700 275);
FORCEPROP 2 LAST SIG_NAME P5E_CPU1_PE4_RX_DP<0>
J 0
(2865 285);
DISPLAY 0.638298 (2865 285);
WIRE 16 -1 (-625 3800)(-775 3800);
WIRE 16 -1 (-775 3650)(-775 3800);
WIRE 16 -1 (-625 3650)(-775 3650);
WIRE 16 -1 (-625 3500)(-775 3500);
WIRE 16 -1 (-775 3500)(-775 3650);
WIRE 16 -1 (-775 3350)(-775 3500);
WIRE 16 -1 (-625 3350)(-775 3350);
WIRE 16 -1 (-775 3200)(-775 3350);
WIRE 16 -1 (-625 3200)(-775 3200);
WIRE 16 -1 (-625 3050)(-775 3050);
WIRE 16 -1 (-775 3050)(-775 3200);
WIRE 16 -1 (-775 2900)(-775 3050);
WIRE 16 -1 (-625 2900)(-775 2900);
WIRE 16 -1 (-775 2650)(-775 2900);
WIRE 16 -1 (-625 2650)(-775 2650);
WIRE 16 -1 (-625 2500)(-775 2500);
WIRE 16 -1 (-775 2500)(-775 2650);
WIRE 16 -1 (-775 2350)(-775 2500);
WIRE 16 -1 (-625 2350)(-775 2350);
WIRE 16 -1 (-775 2200)(-775 2350);
WIRE 16 -1 (-625 2200)(-775 2200);
WIRE 16 -1 (-775 2050)(-775 2200);
WIRE 16 -1 (-625 2050)(-775 2050);
WIRE 16 -1 (-625 1900)(-775 1900);
WIRE 16 -1 (-775 1900)(-775 2050);
WIRE 16 -1 (-775 1750)(-775 1900);
WIRE 16 -1 (-625 1750)(-775 1750);
WIRE 16 -1 (-775 1600)(-775 1750);
WIRE 16 -1 (-625 1600)(-775 1600);
WIRE 16 -1 (-625 1450)(-775 1450);
WIRE 16 -1 (-775 1450)(-775 1600);
WIRE 16 -1 (-775 1300)(-775 1450);
WIRE 16 -1 (-625 1300)(-775 1300);
WIRE 16 -1 (-775 1150)(-775 1300);
WIRE 16 -1 (-625 1150)(-775 1150);
WIRE 16 -1 (-625 1000)(-775 1000);
WIRE 16 -1 (-775 1000)(-775 1150);
WIRE 16 -1 (-775 850)(-775 1000);
WIRE 16 -1 (-625 850)(-775 850);
WIRE 16 -1 (-775 700)(-775 850);
WIRE 16 -1 (-625 700)(-775 700);
WIRE 16 -1 (-625 450)(-775 450);
WIRE 16 -1 (-775 450)(-775 700);
WIRE 16 -1 (-775 300)(-775 450);
WIRE 16 -1 (-625 300)(-775 300);
WIRE 16 -1 (-775 150)(-775 300);
WIRE 16 -1 (-625 150)(-775 150);
WIRE 16 -1 (-775 0)(-775 150);
WIRE 16 -1 (-625 0)(-775 0);
WIRE 16 -1 (-625 -150)(-775 -150);
WIRE 16 -1 (-775 -150)(-775 0);
WIRE 16 -1 (-775 -300)(-775 -150);
WIRE 16 -1 (-625 -300)(-775 -300);
WIRE 16 -1 (-775 -450)(-775 -300);
WIRE 16 -1 (-625 -450)(-775 -450);
WIRE 16 -1 (-625 1100)(-1925 1100);
FORCEPROP 2 LAST SIG_NAME P5E_CPU1_PE4_TX_C_DN<5>
J 0
(-1660 1110);
DISPLAY 0.638298 (-1660 1110);
WIRE 16 -1 (-625 1200)(-1925 1200);
FORCEPROP 2 LAST SIG_NAME P5E_CPU1_PE0_TX_C_DP<10>
J 0
(-1660 1210);
DISPLAY 0.638298 (-1660 1210);
WIRE 16 -1 (-625 2150)(-1950 2150);
FORCEPROP 2 LAST SIG_NAME P5E_CPU1_PE4_TX_C_DN<6>
J 0
(-1660 2160);
DISPLAY 0.638298 (-1660 2160);
WIRE 16 -1 (-625 2400)(-1950 2400);
FORCEPROP 2 LAST SIG_NAME P5E_CPU1_PE4_RX_DP<6>
J 0
(-1660 2410);
DISPLAY 0.638298 (-1660 2410);
WIRE 16 -1 (-625 2250)(-1950 2250);
FORCEPROP 2 LAST SIG_NAME P5E_CPU1_PE0_TX_C_DP<9>
J 0
(-1660 2260);
DISPLAY 0.638298 (-1660 2260);
WIRE 16 -1 (-625 2100)(-1950 2100);
FORCEPROP 2 LAST SIG_NAME P5E_CPU1_PE4_TX_C_DP<6>
J 0
(-1660 2110);
DISPLAY 0.638298 (-1660 2110);
WIRE 16 -1 (3925 3775)(2700 3775);
FORCEPROP 2 LAST SIG_NAME P5E_CPU1_PE0_RX_DP<12>
J 0
(2865 3785);
DISPLAY 0.638298 (2865 3785);
WIRE 16 -1 (3925 825)(2700 825);
FORCEPROP 2 LAST SIG_NAME CLK_100M_GPU_FPGA_DP
J 0
(2865 835);
DISPLAY 0.638298 (2865 835);
WIRE 16 -1 (-625 -50)(-1925 -50);
FORCEPROP 2 LAST SIG_NAME P5E_CPU1_PE4_TX_C_DN<4>
J 0
(-1660 -40);
DISPLAY 0.638298 (-1660 -40);
WIRE 16 -1 (-625 -250)(-1875 -250);
FORCEPROP 2 LAST SIG_NAME NC_J112_P5
J 0
(-1660 -240);
DISPLAY 0.638298 (-1660 -240);
WIRE 16 -1 (-625 -350)(-1875 -350);
FORCEPROP 2 LAST SIG_NAME NC_J112_R5
J 0
(-1660 -340);
DISPLAY 0.638298 (-1660 -340);
WIRE 16 -1 (-625 -400)(-1875 -400);
FORCEPROP 2 LAST SIG_NAME NC_J112_S5
J 0
(-1660 -390);
DISPLAY 0.638298 (-1660 -390);
WIRE 16 -1 (-625 -200)(-1875 -200);
FORCEPROP 2 LAST SIG_NAME NC_J112_O5
J 0
(-1660 -190);
DISPLAY 0.638298 (-1660 -190);
WIRE 16 -1 (-625 -100)(-1925 -100);
FORCEPROP 2 LAST SIG_NAME P5E_CPU1_PE4_TX_C_DP<4>
J 0
(-1660 -90);
DISPLAY 0.638298 (-1660 -90);
WIRE 16 -1 (3925 2375)(2700 2375);
FORCEPROP 2 LAST SIG_NAME P5E_CPU1_PE0_TX_C_DN<13>
J 0
(2865 2385);
DISPLAY 0.638298 (2865 2385);
WIRE 16 -1 (3925 1425)(2700 1425);
FORCEPROP 2 LAST SIG_NAME P5E_CPU1_PE4_RX_DN<1>
J 0
(2865 1435);
DISPLAY 0.638298 (2865 1435);
WIRE 16 -1 (3925 1325)(2700 1325);
FORCEPROP 2 LAST SIG_NAME P5E_CPU1_PE0_TX_C_DN<14>
J 0
(2865 1335);
DISPLAY 0.638298 (2865 1335);
WIRE 16 -1 (3925 1175)(2700 1175);
FORCEPROP 2 LAST SIG_NAME P5E_CPU1_PE4_TX_C_DP<1>
J 0
(2865 1185);
DISPLAY 0.638298 (2865 1185);
WIRE 16 -1 (3925 3475)(2700 3475);
FORCEPROP 2 LAST SIG_NAME P5E_CPU1_PE0_TX_C_DP<12>
J 0
(2865 3485);
DISPLAY 0.638298 (2865 3485);
WIRE 16 -1 (-625 1250)(-1925 1250);
FORCEPROP 2 LAST SIG_NAME P5E_CPU1_PE0_TX_C_DN<10>
J 0
(-1660 1260);
DISPLAY 0.638298 (-1660 1260);
WIRE 16 -1 (-625 400)(-1925 400);
FORCEPROP 2 LAST SIG_NAME P5E_CPU1_PE0_RX_DP<11>
J 0
(-1660 410);
DISPLAY 0.638298 (-1660 410);
WIRE 16 -1 (-625 50)(-1925 50);
FORCEPROP 2 LAST SIG_NAME P5E_CPU1_PE0_TX_C_DP<11>
J 0
(-1660 60);
DISPLAY 0.638298 (-1660 60);
WIRE 16 -1 (3925 -275)(2700 -275);
FORCEPROP 2 LAST SIG_NAME USB2_HUB_BUF_SWB_DN
J 0
(2865 -265);
DISPLAY 0.638298 (2865 -265);
WIRE 16 -1 (3925 3825)(2700 3825);
FORCEPROP 2 LAST SIG_NAME P5E_CPU1_PE0_RX_DN<12>
J 0
(2865 3835);
DISPLAY 0.638298 (2865 3835);
WIRE 16 -1 (3925 3375)(2700 3375);
FORCEPROP 2 LAST SIG_NAME P5E_CPU1_PE4_TX_C_DN<3>
J 0
(2865 3385);
DISPLAY 0.638298 (2865 3385);
WIRE 16 -1 (3925 3525)(2700 3525);
FORCEPROP 2 LAST SIG_NAME P5E_CPU1_PE0_TX_C_DN<12>
J 0
(2865 3535);
DISPLAY 0.638298 (2865 3535);
WIRE 16 -1 (3925 3625)(2700 3625);
FORCEPROP 2 LAST SIG_NAME P5E_CPU1_PE4_RX_DN<3>
J 0
(2865 3635);
DISPLAY 0.638298 (2865 3635);
WIRE 16 -1 (3925 3675)(2700 3675);
FORCEPROP 2 LAST SIG_NAME P5E_CPU1_PE4_RX_DP<3>
J 0
(2865 3685);
DISPLAY 0.638298 (2865 3685);
WIRE 16 -1 (3925 475)(2700 475);
FORCEPROP 2 LAST SIG_NAME P5E_CPU1_PE0_RX_DN<15>
J 0
(2865 485);
DISPLAY 0.638298 (2865 485);
DOT 1 (-775 150);
DOT 1 (-775 1000);
DOT 1 (3775 1225);
DOT 1 (-775 2900);
DOT 1 (-775 2350);
DOT 1 (3775 2425);
DOT 1 (3775 3425);
DOT 1 (3775 -75);
DOT 1 (3775 1675);
DOT 1 (3775 775);
DOT 1 (3775 3125);
DOT 1 (3775 3275);
DOT 1 (3775 2975);
DOT 1 (3775 1075);
DOT 1 (3775 375);
DOT 1 (3775 2725);
DOT 1 (3775 2125);
DOT 1 (3775 525);
DOT 1 (3775 1375);
DOT 1 (3775 3725);
DOT 1 (3775 -375);
DOT 1 (3775 -225);
DOT 1 (3775 3575);
DOT 1 (3775 925);
DOT 1 (3775 1975);
DOT 1 (3775 2275);
DOT 1 (3775 1825);
DOT 1 (3775 1525);
DOT 1 (3775 75);
DOT 1 (3775 225);
DOT 1 (3775 2575);
DOT 1 (-775 -450);
DOT 1 (-775 -300);
DOT 1 (-775 -150);
DOT 1 (-775 0);
DOT 1 (-775 300);
DOT 1 (-775 450);
DOT 1 (-775 700);
DOT 1 (-775 850);
DOT 1 (-775 1150);
DOT 1 (-775 1300);
DOT 1 (-775 1450);
DOT 1 (-775 1750);
DOT 1 (-775 1600);
DOT 1 (-775 1900);
DOT 1 (-775 2050);
DOT 1 (-775 2200);
DOT 1 (-775 2500);
DOT 1 (-775 2650);
DOT 1 (-775 3050);
DOT 1 (-775 3200);
DOT 1 (-775 3500);
DOT 1 (-775 3350);
DOT 1 (-775 3650);
FORCENOTE
DP/DN SWAP
(-2775 1350) 0;
DISPLAY LEFT (-2775 1350);
DISPLAY 1.021277 (-2775 1350);
FORCENOTE
CPU1_PE4_TX/RX<0-15> LANE REVERSAL
(-2725 4200) 0;
DISPLAY LEFT (-2725 4200);
DISPLAY 1.276596 (-2725 4200);
PAINT WHITE (-2725 4200);
FORCENOTE
DP/DN SWAP
(1825 1425) 0;
DISPLAY LEFT (1825 1425);
DISPLAY 1.021277 (1825 1425);
FORCENOTE
20210527 MODIFY FOR GT
(-2725 4675) 0;
DISPLAY LEFT (-2725 4675);
DISPLAY 2.510638 (-2725 4675);
PAINT PINK (-2725 4675);
FORCENOTE
DP/DN SWAP
(-2750 3575) 0;
DISPLAY LEFT (-2750 3575);
DISPLAY 1.021277 (-2750 3575);
FORCENOTE
DP/DN SWAP
(-2775 350) 0;
DISPLAY LEFT (-2775 350);
DISPLAY 1.021277 (-2775 350);
FORCENOTE
DP/DN SWAP
(1825 1125) 0;
DISPLAY LEFT (1825 1125);
DISPLAY 1.021277 (1825 1125);
FORCENOTE
DP/DN SWAP
(1850 3625) 0;
DISPLAY LEFT (1850 3625);
DISPLAY 1.021277 (1850 3625);
QUIT
